G04 ================== begin FILE IDENTIFICATION RECORD ==================*
G04 Layout Name:  15669-1.brd*
G04 Film Name:    L4VCC*
G04 File Format:  Gerber RS274X*
G04 File Origin:  Cadence Allegro 16.5-S056*
G04 Origin Date:  Wed Nov 16 04:08:46 2016*
G04 *
G04 Layer:  VIA CLASS/L4VCC*
G04 Layer:  PIN/L4VCC*
G04 Layer:  PACKAGE GEOMETRY/PWRVCC*
G04 Layer:  ETCH/L4VCC*
G04 Layer:  DRAWING FORMAT/LAYER_PCB_STORY*
G04 Layer:  DRAWING FORMAT/LAYER_L4VCC*
G04 *
G04 Offset:    (0.00 0.00)*
G04 Mirror:    No*
G04 Mode:      Negative*
G04 Rotation:  0*
G04 FullContactRelief:  No*
G04 UndefLineWidth:     6.00*
G04 ================== end FILE IDENTIFICATION RECORD ====================*
%FSLAX35Y35*MOIN*%
%IR0*IPPOS*OFA0.00000B0.00000*MIA0B0*SFA1.00000B1.00000*%
%ADD22O,.115X.072*%
%ADD16C,.03*%
%ADD17C,.032*%
%ADD21C,.036*%
%AMMACRO19*
4,1,15,.00398,.00044,
.003999,.000208,
.004004,-.000025,
.003996,-.000258,
.00398,-.00044,
.00483,-.00129,
.004897,-.001007,
.004947,-.000721,
.004981,-.000432,
.004997,-.000141,
.004997,.000149,
.00498,.00044,
.004946,.000729,
.004895,.001015,
.00483,.00129,
.00398,.00044,
90.*
4,1,15,.00044,-.00398,
.000208,-.003999,
-.000025,-.004004,
-.000258,-.003996,
-.00044,-.00398,
-.00129,-.00483,
-.001007,-.004897,
-.000721,-.004947,
-.000432,-.004981,
-.000141,-.004997,
.000149,-.004997,
.00044,-.00498,
.000729,-.004946,
.001015,-.004895,
.00129,-.00483,
.00044,-.00398,
90.*
4,1,15,-.00398,-.00044,
-.003999,-.000208,
-.004004,.000025,
-.003996,.000258,
-.00398,.00044,
-.00483,.00129,
-.004897,.001007,
-.004947,.000721,
-.004981,.000432,
-.004997,.000141,
-.004997,-.000149,
-.00498,-.00044,
-.004946,-.000729,
-.004895,-.001015,
-.00483,-.00129,
-.00398,-.00044,
90.*
4,1,15,-.00044,.00398,
-.000208,.003999,
.000025,.004004,
.000258,.003996,
.00044,.00398,
.00129,.00483,
.001007,.004897,
.000721,.004947,
.000432,.004981,
.000141,.004997,
-.000149,.004997,
-.00044,.00498,
-.000729,.004946,
-.001015,.004895,
-.00129,.00483,
-.00044,.00398,
90.*
%
%ADD19MACRO19*%
%AMMACRO11*
4,1,15,.00398,.00044,
.003999,.000208,
.004004,-.000025,
.003996,-.000258,
.00398,-.00044,
.00483,-.00129,
.004897,-.001007,
.004947,-.000721,
.004981,-.000432,
.004997,-.000141,
.004997,.000149,
.00498,.00044,
.004946,.000729,
.004895,.001015,
.00483,.00129,
.00398,.00044,
0.0*
4,1,15,.00044,-.00398,
.000208,-.003999,
-.000025,-.004004,
-.000258,-.003996,
-.00044,-.00398,
-.00129,-.00483,
-.001007,-.004897,
-.000721,-.004947,
-.000432,-.004981,
-.000141,-.004997,
.000149,-.004997,
.00044,-.00498,
.000729,-.004946,
.001015,-.004895,
.00129,-.00483,
.00044,-.00398,
0.0*
4,1,15,-.00398,-.00044,
-.003999,-.000208,
-.004004,.000025,
-.003996,.000258,
-.00398,.00044,
-.00483,.00129,
-.004897,.001007,
-.004947,.000721,
-.004981,.000432,
-.004997,.000141,
-.004997,-.000149,
-.00498,-.00044,
-.004946,-.000729,
-.004895,-.001015,
-.00483,-.00129,
-.00398,-.00044,
0.0*
4,1,15,-.00044,.00398,
-.000208,.003999,
.000025,.004004,
.000258,.003996,
.00044,.00398,
.00129,.00483,
.001007,.004897,
.000721,.004947,
.000432,.004981,
.000141,.004997,
-.000149,.004997,
-.00044,.00498,
-.000729,.004946,
-.001015,.004895,
-.00129,.00483,
-.00044,.00398,
0.0*
%
%ADD11MACRO11*%
%AMMACRO20*
4,1,15,-.00398,.00044,
-.003999,.000208,
-.004004,-.000025,
-.003996,-.000258,
-.00398,-.00044,
-.00483,-.00129,
-.004897,-.001007,
-.004947,-.000721,
-.004981,-.000432,
-.004997,-.000141,
-.004997,.000149,
-.00498,.00044,
-.004946,.000729,
-.004895,.001015,
-.00483,.00129,
-.00398,.00044,
0.0*
4,1,15,-.00044,-.00398,
-.000208,-.003999,
.000025,-.004004,
.000258,-.003996,
.00044,-.00398,
.00129,-.00483,
.001007,-.004897,
.000721,-.004947,
.000432,-.004981,
.000141,-.004997,
-.000149,-.004997,
-.00044,-.00498,
-.000729,-.004946,
-.001015,-.004895,
-.00129,-.00483,
-.00044,-.00398,
0.0*
4,1,15,.00398,-.00044,
.003999,-.000208,
.004004,.000025,
.003996,.000258,
.00398,.00044,
.00483,.00129,
.004897,.001007,
.004947,.000721,
.004981,.000432,
.004997,.000141,
.004997,-.000149,
.00498,-.00044,
.004946,-.000729,
.004895,-.001015,
.00483,-.00129,
.00398,-.00044,
0.0*
4,1,15,.00044,.00398,
.000208,.003999,
-.000025,.004004,
-.000258,.003996,
-.00044,.00398,
-.00129,.00483,
-.001007,.004897,
-.000721,.004947,
-.000432,.004981,
-.000141,.004997,
.000149,.004997,
.00044,.00498,
.000729,.004946,
.001015,.004895,
.00129,.00483,
.00044,.00398,
0.0*
%
%ADD20MACRO20*%
%ADD23C,.101*%
%ADD10C,.114*%
%ADD14C,.115*%
%ADD18C,.18*%
%ADD28C,.174*%
%AMMACRO27*
4,1,15,.00398,.00044,
.003999,.000208,
.004004,-.000025,
.003996,-.000258,
.00398,-.00044,
.00483,-.00129,
.004897,-.001007,
.004947,-.000721,
.004981,-.000432,
.004997,-.000141,
.004997,.000149,
.00498,.00044,
.004946,.000729,
.004895,.001015,
.00483,.00129,
.00398,.00044,
135.*
4,1,15,.00044,-.00398,
.000208,-.003999,
-.000025,-.004004,
-.000258,-.003996,
-.00044,-.00398,
-.00129,-.00483,
-.001007,-.004897,
-.000721,-.004947,
-.000432,-.004981,
-.000141,-.004997,
.000149,-.004997,
.00044,-.00498,
.000729,-.004946,
.001015,-.004895,
.00129,-.00483,
.00044,-.00398,
135.*
4,1,15,-.00398,-.00044,
-.003999,-.000208,
-.004004,.000025,
-.003996,.000258,
-.00398,.00044,
-.00483,.00129,
-.004897,.001007,
-.004947,.000721,
-.004981,.000432,
-.004997,.000141,
-.004997,-.000149,
-.00498,-.00044,
-.004946,-.000729,
-.004895,-.001015,
-.00483,-.00129,
-.00398,-.00044,
135.*
4,1,15,-.00044,.00398,
-.000208,.003999,
.000025,.004004,
.000258,.003996,
.00044,.00398,
.00129,.00483,
.001007,.004897,
.000721,.004947,
.000432,.004981,
.000141,.004997,
-.000149,.004997,
-.00044,.00498,
-.000729,.004946,
-.001015,.004895,
-.00129,.00483,
-.00044,.00398,
135.*
%
%ADD27MACRO27*%
%AMMACRO25*
4,1,15,.00398,.00044,
.003999,.000208,
.004004,-.000025,
.003996,-.000258,
.00398,-.00044,
.00483,-.00129,
.004897,-.001007,
.004947,-.000721,
.004981,-.000432,
.004997,-.000141,
.004997,.000149,
.00498,.00044,
.004946,.000729,
.004895,.001015,
.00483,.00129,
.00398,.00044,
270.*
4,1,15,.00044,-.00398,
.000208,-.003999,
-.000025,-.004004,
-.000258,-.003996,
-.00044,-.00398,
-.00129,-.00483,
-.001007,-.004897,
-.000721,-.004947,
-.000432,-.004981,
-.000141,-.004997,
.000149,-.004997,
.00044,-.00498,
.000729,-.004946,
.001015,-.004895,
.00129,-.00483,
.00044,-.00398,
270.*
4,1,15,-.00398,-.00044,
-.003999,-.000208,
-.004004,.000025,
-.003996,.000258,
-.00398,.00044,
-.00483,.00129,
-.004897,.001007,
-.004947,.000721,
-.004981,.000432,
-.004997,.000141,
-.004997,-.000149,
-.00498,-.00044,
-.004946,-.000729,
-.004895,-.001015,
-.00483,-.00129,
-.00398,-.00044,
270.*
4,1,15,-.00044,.00398,
-.000208,.003999,
.000025,.004004,
.000258,.003996,
.00044,.00398,
.00129,.00483,
.001007,.004897,
.000721,.004947,
.000432,.004981,
.000141,.004997,
-.000149,.004997,
-.00044,.00498,
-.000729,.004946,
-.001015,.004895,
-.00129,.00483,
-.00044,.00398,
270.*
%
%ADD25MACRO25*%
%AMMACRO24*
4,1,15,.00398,.00044,
.003999,.000208,
.004004,-.000025,
.003996,-.000258,
.00398,-.00044,
.00483,-.00129,
.004897,-.001007,
.004947,-.000721,
.004981,-.000432,
.004997,-.000141,
.004997,.000149,
.00498,.00044,
.004946,.000729,
.004895,.001015,
.00483,.00129,
.00398,.00044,
315.*
4,1,15,.00044,-.00398,
.000208,-.003999,
-.000025,-.004004,
-.000258,-.003996,
-.00044,-.00398,
-.00129,-.00483,
-.001007,-.004897,
-.000721,-.004947,
-.000432,-.004981,
-.000141,-.004997,
.000149,-.004997,
.00044,-.00498,
.000729,-.004946,
.001015,-.004895,
.00129,-.00483,
.00044,-.00398,
315.*
4,1,15,-.00398,-.00044,
-.003999,-.000208,
-.004004,.000025,
-.003996,.000258,
-.00398,.00044,
-.00483,.00129,
-.004897,.001007,
-.004947,.000721,
-.004981,.000432,
-.004997,.000141,
-.004997,-.000149,
-.00498,-.00044,
-.004946,-.000729,
-.004895,-.001015,
-.00483,-.00129,
-.00398,-.00044,
315.*
4,1,15,-.00044,.00398,
-.000208,.003999,
.000025,.004004,
.000258,.003996,
.00044,.00398,
.00129,.00483,
.001007,.004897,
.000721,.004947,
.000432,.004981,
.000141,.004997,
-.000149,.004997,
-.00044,.00498,
-.000729,.004946,
-.001015,.004895,
-.00129,.00483,
-.00044,.00398,
315.*
%
%ADD24MACRO24*%
%AMMACRO13*
4,1,15,.00398,.00044,
.003999,.000208,
.004004,-.000025,
.003996,-.000258,
.00398,-.00044,
.00483,-.00129,
.004897,-.001007,
.004947,-.000721,
.004981,-.000432,
.004997,-.000141,
.004997,.000149,
.00498,.00044,
.004946,.000729,
.004895,.001015,
.00483,.00129,
.00398,.00044,
180.*
4,1,15,.00044,-.00398,
.000208,-.003999,
-.000025,-.004004,
-.000258,-.003996,
-.00044,-.00398,
-.00129,-.00483,
-.001007,-.004897,
-.000721,-.004947,
-.000432,-.004981,
-.000141,-.004997,
.000149,-.004997,
.00044,-.00498,
.000729,-.004946,
.001015,-.004895,
.00129,-.00483,
.00044,-.00398,
180.*
4,1,15,-.00398,-.00044,
-.003999,-.000208,
-.004004,.000025,
-.003996,.000258,
-.00398,.00044,
-.00483,.00129,
-.004897,.001007,
-.004947,.000721,
-.004981,.000432,
-.004997,.000141,
-.004997,-.000149,
-.00498,-.00044,
-.004946,-.000729,
-.004895,-.001015,
-.00483,-.00129,
-.00398,-.00044,
180.*
4,1,15,-.00044,.00398,
-.000208,.003999,
.000025,.004004,
.000258,.003996,
.00044,.00398,
.00129,.00483,
.001007,.004897,
.000721,.004947,
.000432,.004981,
.000141,.004997,
-.000149,.004997,
-.00044,.00498,
-.000729,.004946,
-.001015,.004895,
-.00129,.00483,
-.00044,.00398,
180.*
%
%ADD13MACRO13*%
%AMMACRO26*
4,1,15,-.00398,.00044,
-.003999,.000208,
-.004004,-.000025,
-.003996,-.000258,
-.00398,-.00044,
-.00483,-.00129,
-.004897,-.001007,
-.004947,-.000721,
-.004981,-.000432,
-.004997,-.000141,
-.004997,.000149,
-.00498,.00044,
-.004946,.000729,
-.004895,.001015,
-.00483,.00129,
-.00398,.00044,
270.*
4,1,15,-.00044,-.00398,
-.000208,-.003999,
.000025,-.004004,
.000258,-.003996,
.00044,-.00398,
.00129,-.00483,
.001007,-.004897,
.000721,-.004947,
.000432,-.004981,
.000141,-.004997,
-.000149,-.004997,
-.00044,-.00498,
-.000729,-.004946,
-.001015,-.004895,
-.00129,-.00483,
-.00044,-.00398,
270.*
4,1,15,.00398,-.00044,
.003999,-.000208,
.004004,.000025,
.003996,.000258,
.00398,.00044,
.00483,.00129,
.004897,.001007,
.004947,.000721,
.004981,.000432,
.004997,.000141,
.004997,-.000149,
.00498,-.00044,
.004946,-.000729,
.004895,-.001015,
.00483,-.00129,
.00398,-.00044,
270.*
4,1,15,.00044,.00398,
.000208,.003999,
-.000025,.004004,
-.000258,.003996,
-.00044,.00398,
-.00129,.00483,
-.001007,.004897,
-.000721,.004947,
-.000432,.004981,
-.000141,.004997,
.000149,.004997,
.00044,.00498,
.000729,.004946,
.001015,.004895,
.00129,.00483,
.00044,.00398,
270.*
%
%ADD26MACRO26*%
%AMMACRO15*
4,1,15,-.00398,.00044,
-.003999,.000208,
-.004004,-.000025,
-.003996,-.000258,
-.00398,-.00044,
-.00483,-.00129,
-.004897,-.001007,
-.004947,-.000721,
-.004981,-.000432,
-.004997,-.000141,
-.004997,.000149,
-.00498,.00044,
-.004946,.000729,
-.004895,.001015,
-.00483,.00129,
-.00398,.00044,
180.*
4,1,15,-.00044,-.00398,
-.000208,-.003999,
.000025,-.004004,
.000258,-.003996,
.00044,-.00398,
.00129,-.00483,
.001007,-.004897,
.000721,-.004947,
.000432,-.004981,
.000141,-.004997,
-.000149,-.004997,
-.00044,-.00498,
-.000729,-.004946,
-.001015,-.004895,
-.00129,-.00483,
-.00044,-.00398,
180.*
4,1,15,.00398,-.00044,
.003999,-.000208,
.004004,.000025,
.003996,.000258,
.00398,.00044,
.00483,.00129,
.004897,.001007,
.004947,.000721,
.004981,.000432,
.004997,.000141,
.004997,-.000149,
.00498,-.00044,
.004946,-.000729,
.004895,-.001015,
.00483,-.00129,
.00398,-.00044,
180.*
4,1,15,.00044,.00398,
.000208,.003999,
-.000025,.004004,
-.000258,.003996,
-.00044,.00398,
-.00129,.00483,
-.001007,.004897,
-.000721,.004947,
-.000432,.004981,
-.000141,.004997,
.000149,.004997,
.00044,.00498,
.000729,.004946,
.001015,.004895,
.00129,.00483,
.00044,.00398,
180.*
%
%ADD15MACRO15*%
%ADD29C,.02*%
%ADD30C,.006*%
%ADD34C,.09704*%
%ADD33C,.11004*%
%ADD31C,.11104*%
%ADD35C,.17004*%
%ADD32C,.39404*%
G75*
%LPD*%
G75*
G36*
G01X-6000Y-6000D02*
X1043402D01*
Y1998126D01*
X-6000D01*
Y-6000D01*
G37*
%LPC*%
G75*
G36*
G01X124665Y13315D02*
X119419Y3004D01*
X3937D01*
G02X3004Y3937I0J933D01*
G01Y596998D01*
X13760D01*
Y734169D01*
X17323D01*
G03Y748839I0J7335D01*
G01X13760D01*
Y924002D01*
X3004D01*
Y1092998D01*
X13760D01*
Y1230232D01*
X17323D01*
G03Y1244902I0J7335D01*
G01X13760D01*
Y1420002D01*
X3004D01*
Y1510498D01*
X13760D01*
Y1647555D01*
X17323D01*
G03Y1662224I0J7335D01*
G01X13760D01*
Y1838002D01*
X3004D01*
Y1988189D01*
G02X3937Y1989122I933J0D01*
G01X1033465D01*
G02X1034398Y1988189I0J-933D01*
G01Y1686599D01*
X1032220Y1684421D01*
X1028700D01*
G03X1020224Y1675945I0J-8476D01*
G01Y1621265D01*
X1018046Y1619087D01*
X993681D01*
G03Y1608866I0J-5110D01*
G01X1018046D01*
X1020224Y1606688D01*
Y1434291D01*
G03X1028700Y1425815I8477J1D01*
G01X1032220D01*
X1034398Y1423637D01*
Y3937D01*
G02X1033465Y3004I-933J0D01*
G01X148298D01*
X143084Y13251D01*
G02X142768Y14565I2585J1317D01*
G01Y17717D01*
G03X124949I-8909J0D01*
G01Y14565D01*
G02X124665Y13315I-2902J2D01*
G37*
%LPD*%
G75*
G36*
G01X1005938Y1903534D02*
Y1900889D01*
G03X1007242Y1897199I5875J1D01*
G02X988819I-9211J-7446D01*
G03X990122Y1900889I-4571J3689D01*
G01Y1903534D01*
G02X1005938I7908J0D01*
G37*
G36*
G01Y1082667D02*
Y1080022D01*
G03X1007242Y1076332I5875J1D01*
G02X988819I-9211J-7446D01*
G03X990122Y1080022I-4571J3689D01*
G01Y1082667D01*
G02X1005938I7908J0D01*
G37*
G36*
G01Y686998D02*
Y684353D01*
G03X1007242Y680663I5875J1D01*
G02X988819I-9211J-7446D01*
G03X990122Y684353I-4571J3689D01*
G01Y686998D01*
G02X1005938I7908J0D01*
G37*
G36*
G01Y163376D02*
Y160731D01*
G03X1007242Y157041I5875J1D01*
G02X988819I-9211J-7446D01*
G03X990122Y160731I-4571J3689D01*
G01Y163376D01*
G02X1005938I7908J0D01*
G37*
G36*
G01X920858Y1860549D02*
G02X916834I-2012J0D01*
G01Y1863750D01*
G02X920858Y1863749I2012J-1D01*
G01Y1860549D01*
G37*
G36*
G01Y1455037D02*
G02X916834I-2012J0D01*
G01Y1458238D01*
G02X920858Y1458237I2012J-1D01*
G01Y1455037D01*
G37*
G36*
G01Y1049525D02*
G02X916834I-2012J0D01*
G01Y1052726D01*
G02X920858Y1052725I2012J-1D01*
G01Y1049525D01*
G37*
G36*
G01Y644013D02*
G02X916834I-2012J0D01*
G01Y647214D01*
G02X920858Y647213I2012J-1D01*
G01Y644013D01*
G37*
G36*
G01Y238501D02*
G02X916834I-2012J0D01*
G01Y241702D01*
G02X920858Y241701I2012J-1D01*
G01Y238501D01*
G37*
G36*
G01X865430Y1909435D02*
G02X869452I2011J0D01*
G01Y1906234D01*
G02X865430Y1906235I-2011J1D01*
G01Y1909435D01*
G37*
G36*
G01Y1890538D02*
G02X869452I2011J0D01*
G01Y1887337D01*
G02X865430Y1887338I-2011J1D01*
G01Y1890538D01*
G37*
G36*
G01X870530Y1919484D02*
G02X875352I2411J0D01*
G01Y1915083D01*
G02X870530Y1915084I-2411J1D01*
G01Y1919484D01*
G37*
G36*
G01Y1900586D02*
G02X875352I2411J0D01*
G01Y1896185D01*
G02X870530Y1896186I-2411J1D01*
G01Y1900586D01*
G37*
G36*
G01X865430Y1928333D02*
G02X869452I2011J0D01*
G01Y1925132D01*
G02X865430Y1925133I-2011J1D01*
G01Y1928333D01*
G37*
G36*
G01X870530Y1938382D02*
G02X875352I2411J0D01*
G01Y1933981D01*
G02X870530Y1933982I-2411J1D01*
G01Y1938382D01*
G37*
G36*
G01X865430Y1840144D02*
G02X869452I2011J0D01*
G01Y1836943D01*
G02X865430Y1836944I-2011J1D01*
G01Y1840144D01*
G37*
G36*
G01X870530Y1850193D02*
G02X875352I2411J0D01*
G01Y1845792D01*
G02X870530Y1845793I-2411J1D01*
G01Y1850193D01*
G37*
G36*
G01X905146Y1855430D02*
G02Y1859454I0J2012D01*
G01X908347D01*
G02X908346Y1855430I-1J-2012D01*
G01X905146D01*
G37*
G36*
G01X865430Y1522821D02*
G02X869452I2011J0D01*
G01Y1519620D01*
G02X865430Y1519621I-2011J1D01*
G01Y1522821D01*
G37*
G36*
G01X870530Y1532870D02*
G02X875352I2411J0D01*
G01Y1528469D01*
G02X870530Y1528470I-2411J1D01*
G01Y1532870D01*
G37*
G36*
G01Y1513972D02*
G02X875352I2411J0D01*
G01Y1509571D01*
G02X870530Y1509572I-2411J1D01*
G01Y1513972D01*
G37*
G36*
G01X865430Y1485026D02*
G02X869452I2011J0D01*
G01Y1481825D01*
G02X865430Y1481826I-2011J1D01*
G01Y1485026D01*
G37*
G36*
G01X870530Y1444681D02*
G02X875352I2411J0D01*
G01Y1440280D01*
G02X870530Y1440281I-2411J1D01*
G01Y1444681D01*
G37*
G36*
G01X865430Y1503923D02*
G02X869452I2011J0D01*
G01Y1500722D01*
G02X865430Y1500723I-2011J1D01*
G01Y1503923D01*
G37*
G36*
G01X870530Y1495074D02*
G02X875352I2411J0D01*
G01Y1490673D01*
G02X870530Y1490674I-2411J1D01*
G01Y1495074D01*
G37*
G36*
G01X905146Y1449918D02*
G02Y1453942I0J2012D01*
G01X908347D01*
G02X908346Y1449918I-1J-2012D01*
G01X905146D01*
G37*
G36*
G01X865430Y1434632D02*
G02X869452I2011J0D01*
G01Y1431431D01*
G02X865430Y1431432I-2011J1D01*
G01Y1434632D01*
G37*
G36*
G01Y1098411D02*
G02X869452I2011J0D01*
G01Y1095210D01*
G02X865430Y1095211I-2011J1D01*
G01Y1098411D01*
G37*
G36*
G01Y1117309D02*
G02X869452I2011J0D01*
G01Y1114108D01*
G02X865430Y1114109I-2011J1D01*
G01Y1117309D01*
G37*
G36*
G01X870530Y1108460D02*
G02X875352I2411J0D01*
G01Y1104059D01*
G02X870530Y1104060I-2411J1D01*
G01Y1108460D01*
G37*
G36*
G01Y1089562D02*
G02X875352I2411J0D01*
G01Y1085161D01*
G02X870530Y1085162I-2411J1D01*
G01Y1089562D01*
G37*
G36*
G01X865430Y1079514D02*
G02X869452I2011J0D01*
G01Y1076313D01*
G02X865430Y1076314I-2011J1D01*
G01Y1079514D01*
G37*
G36*
G01X870530Y1127358D02*
G02X875352I2411J0D01*
G01Y1122957D01*
G02X870530Y1122958I-2411J1D01*
G01Y1127358D01*
G37*
G36*
G01X865430Y1029120D02*
G02X869452I2011J0D01*
G01Y1025919D01*
G02X865430Y1025920I-2011J1D01*
G01Y1029120D01*
G37*
G36*
G01X870530Y1039169D02*
G02X875352I2411J0D01*
G01Y1034768D01*
G02X870530Y1034769I-2411J1D01*
G01Y1039169D01*
G37*
G36*
G01X905146Y1044406D02*
G02Y1048430I0J2012D01*
G01X908347D01*
G02X908346Y1044406I-1J-2012D01*
G01X905146D01*
G37*
G36*
G01X865430Y711797D02*
G02X869452I2011J0D01*
G01Y708596D01*
G02X865430Y708597I-2011J1D01*
G01Y711797D01*
G37*
G36*
G01X870530Y721846D02*
G02X875352I2411J0D01*
G01Y717445D01*
G02X870530Y717446I-2411J1D01*
G01Y721846D01*
G37*
G36*
G01X865430Y674002D02*
G02X869452I2011J0D01*
G01Y670801D01*
G02X865430Y670802I-2011J1D01*
G01Y674002D01*
G37*
G36*
G01X870530Y684050D02*
G02X875352I2411J0D01*
G01Y679649D01*
G02X870530Y679650I-2411J1D01*
G01Y684050D01*
G37*
G36*
G01X865430Y692899D02*
G02X869452I2011J0D01*
G01Y689698D01*
G02X865430Y689699I-2011J1D01*
G01Y692899D01*
G37*
G36*
G01X870530Y702948D02*
G02X875352I2411J0D01*
G01Y698547D01*
G02X870530Y698548I-2411J1D01*
G01Y702948D01*
G37*
G36*
G01X905146Y638894D02*
G02Y642918I0J2012D01*
G01X908347D01*
G02X908346Y638894I-1J-2012D01*
G01X905146D01*
G37*
G36*
G01X865430Y623608D02*
G02X869452I2011J0D01*
G01Y620407D01*
G02X865430Y620408I-2011J1D01*
G01Y623608D01*
G37*
G36*
G01X870530Y633657D02*
G02X875352I2411J0D01*
G01Y629256D01*
G02X870530Y629257I-2411J1D01*
G01Y633657D01*
G37*
G36*
G01X865430Y287387D02*
G02X869452I2011J0D01*
G01Y284186D01*
G02X865430Y284187I-2011J1D01*
G01Y287387D01*
G37*
G36*
G01Y306285D02*
G02X869452I2011J0D01*
G01Y303084D01*
G02X865430Y303085I-2011J1D01*
G01Y306285D01*
G37*
G36*
G01X870530Y316334D02*
G02X875352I2411J0D01*
G01Y311933D01*
G02X870530Y311934I-2411J1D01*
G01Y316334D01*
G37*
G36*
G01Y297436D02*
G02X875352I2411J0D01*
G01Y293035D01*
G02X870530Y293036I-2411J1D01*
G01Y297436D01*
G37*
G36*
G01Y278538D02*
G02X875352I2411J0D01*
G01Y274137D01*
G02X870530Y274138I-2411J1D01*
G01Y278538D01*
G37*
G36*
G01X865430Y218096D02*
G02X869452I2011J0D01*
G01Y214895D01*
G02X865430Y214896I-2011J1D01*
G01Y218096D01*
G37*
G36*
G01X870530Y228145D02*
G02X875352I2411J0D01*
G01Y223744D01*
G02X870530Y223745I-2411J1D01*
G01Y228145D01*
G37*
G36*
G01X865430Y268490D02*
G02X869452I2011J0D01*
G01Y265289D01*
G02X865430Y265290I-2011J1D01*
G01Y268490D01*
G37*
G36*
G01X905146Y233382D02*
G02Y237406I0J2012D01*
G01X908347D01*
G02X908346Y233382I-1J-2012D01*
G01X905146D01*
G37*
G36*
G01X283498Y1903534D02*
Y1900889D01*
G03X284802Y1897199I5875J1D01*
G02X266379I-9211J-7446D01*
G03X267682Y1900889I-4571J3689D01*
G01Y1903534D01*
G02X283498I7908J0D01*
G37*
G36*
G01X295600Y1695412D02*
G02Y1691388I0J-2012D01*
G01X292399D01*
G02X292400Y1695412I1J2012D01*
G01X295600D01*
G37*
G36*
G01X282988Y1700600D02*
G02X287012I2012J0D01*
G01Y1697399D01*
G02X282988Y1697400I-2012J1D01*
G01Y1700600D01*
G37*
G36*
G01X283498Y1088573D02*
Y1085928D01*
G03X284802Y1082238I5875J1D01*
G02X266379I-9211J-7446D01*
G03X267682Y1085928I-4571J3689D01*
G01Y1088573D01*
G02X283498I7908J0D01*
G37*
G36*
G01Y685030D02*
Y682385D01*
G03X284802Y678695I5875J1D01*
G02X266379I-9211J-7446D01*
G03X267682Y682385I-4571J3689D01*
G01Y685030D01*
G02X283498I7908J0D01*
G37*
G36*
G01Y279528D02*
Y276883D01*
G03X284802Y273193I5875J1D01*
G02X266379I-9211J-7446D01*
G03X267682Y276883I-4571J3689D01*
G01Y279528D01*
G02X283498I7908J0D01*
G37*
G36*
G01X188488Y1863749D02*
G02X192512I2012J0D01*
G01Y1860548D01*
G02X188488Y1860549I-2012J1D01*
G01Y1863749D01*
G37*
G36*
G01Y1458237D02*
G02X192512I2012J0D01*
G01Y1455036D01*
G02X188488Y1455037I-2012J1D01*
G01Y1458237D01*
G37*
G36*
G01Y1052725D02*
G02X192512I2012J0D01*
G01Y1049524D01*
G02X188488Y1049525I-2012J1D01*
G01Y1052725D01*
G37*
G36*
G01Y647213D02*
G02X192512I2012J0D01*
G01Y644012D01*
G02X188488Y644013I-2012J1D01*
G01Y647213D01*
G37*
G36*
G01Y241701D02*
G02X192512I2012J0D01*
G01Y238500D01*
G02X188488Y238501I-2012J1D01*
G01Y241701D01*
G37*
G36*
G01X141106Y1925133D02*
G02X137084I-2011J0D01*
G01Y1928334D01*
G02X141106Y1928333I2011J-1D01*
G01Y1925133D01*
G37*
G36*
G01Y1906235D02*
G02X137084I-2011J0D01*
G01Y1909436D01*
G02X141106Y1909435I2011J-1D01*
G01Y1906235D01*
G37*
G36*
G01Y1887338D02*
G02X137084I-2011J0D01*
G01Y1890539D01*
G02X141106Y1890538I2011J-1D01*
G01Y1887338D01*
G37*
G36*
G01X147006Y1933982D02*
G02X142184I-2411J0D01*
G01Y1938383D01*
G02X147006Y1938382I2411J-1D01*
G01Y1933982D01*
G37*
G36*
G01X142184Y1919484D02*
G02X147006I2411J0D01*
G01Y1915083D01*
G02X142184Y1915084I-2411J1D01*
G01Y1919484D01*
G37*
G36*
G01X147006Y1896186D02*
G02X142184I-2411J0D01*
G01Y1900587D01*
G02X147006Y1900586I2411J-1D01*
G01Y1896186D01*
G37*
G36*
G01X176800Y1855430D02*
G02Y1859454I0J2012D01*
G01X180001D01*
G02X180000Y1855430I-1J-2012D01*
G01X176800D01*
G37*
G36*
G01X141106Y1836944D02*
G02X137084I-2011J0D01*
G01Y1840145D01*
G02X141106Y1840144I2011J-1D01*
G01Y1836944D01*
G37*
G36*
G01X147006Y1845793D02*
G02X142184I-2411J0D01*
G01Y1850194D01*
G02X147006Y1850193I2411J-1D01*
G01Y1845793D01*
G37*
G36*
G01X122988Y1753534D02*
G02X127012I2012J0D01*
G01Y1750333D01*
G02X122988Y1750334I-2012J1D01*
G01Y1753534D01*
G37*
G36*
G01X137084Y1522821D02*
G02X141106I2011J0D01*
G01Y1519620D01*
G02X137084Y1519621I-2011J1D01*
G01Y1522821D01*
G37*
G36*
G01X142184Y1513972D02*
G02X147006I2411J0D01*
G01Y1509571D01*
G02X142184Y1509572I-2411J1D01*
G01Y1513972D01*
G37*
G36*
G01Y1532870D02*
G02X147006I2411J0D01*
G01Y1528469D01*
G02X142184Y1528470I-2411J1D01*
G01Y1532870D01*
G37*
G36*
G01X180000Y1453942D02*
G02Y1449918I0J-2012D01*
G01X176799D01*
G02X176800Y1453942I1J2012D01*
G01X180000D01*
G37*
G36*
G01X137084Y1503923D02*
G02X141106I2011J0D01*
G01Y1500722D01*
G02X137084Y1500723I-2011J1D01*
G01Y1503923D01*
G37*
G36*
G01Y1485026D02*
G02X141106I2011J0D01*
G01Y1481825D01*
G02X137084Y1481826I-2011J1D01*
G01Y1485026D01*
G37*
G36*
G01X142184Y1495074D02*
G02X147006I2411J0D01*
G01Y1490673D01*
G02X142184Y1490674I-2411J1D01*
G01Y1495074D01*
G37*
G36*
G01Y1444681D02*
G02X147006I2411J0D01*
G01Y1440280D01*
G02X142184Y1440281I-2411J1D01*
G01Y1444681D01*
G37*
G36*
G01X137084Y1434632D02*
G02X141106I2011J0D01*
G01Y1431431D01*
G02X137084Y1431432I-2011J1D01*
G01Y1434632D01*
G37*
G36*
G01X127488Y1348021D02*
G02X131512I2012J0D01*
G01Y1344820D01*
G02X127488Y1344821I-2012J1D01*
G01Y1348021D01*
G37*
G36*
G01X137084Y1117309D02*
G02X141106I2011J0D01*
G01Y1114108D01*
G02X137084Y1114109I-2011J1D01*
G01Y1117309D01*
G37*
G36*
G01Y1098411D02*
G02X141106I2011J0D01*
G01Y1095210D01*
G02X137084Y1095211I-2011J1D01*
G01Y1098411D01*
G37*
G36*
G01Y1079514D02*
G02X141106I2011J0D01*
G01Y1076313D01*
G02X137084Y1076314I-2011J1D01*
G01Y1079514D01*
G37*
G36*
G01X142184Y1089562D02*
G02X147006I2411J0D01*
G01Y1085161D01*
G02X142184Y1085162I-2411J1D01*
G01Y1089562D01*
G37*
G36*
G01Y1108460D02*
G02X147006I2411J0D01*
G01Y1104059D01*
G02X142184Y1104060I-2411J1D01*
G01Y1108460D01*
G37*
G36*
G01Y1127358D02*
G02X147006I2411J0D01*
G01Y1122957D01*
G02X142184Y1122958I-2411J1D01*
G01Y1127358D01*
G37*
G36*
G01X180000Y1048430D02*
G02Y1044406I0J-2012D01*
G01X176799D01*
G02X176800Y1048430I1J2012D01*
G01X180000D01*
G37*
G36*
G01X137084Y1029120D02*
G02X141106I2011J0D01*
G01Y1025919D01*
G02X137084Y1025920I-2011J1D01*
G01Y1029120D01*
G37*
G36*
G01X142184Y1039169D02*
G02X147006I2411J0D01*
G01Y1034768D01*
G02X142184Y1034769I-2411J1D01*
G01Y1039169D01*
G37*
G36*
G01X164988Y942509D02*
G02X169012I2012J0D01*
G01Y939308D01*
G02X164988Y939309I-2012J1D01*
G01Y942509D01*
G37*
G36*
G01X137084Y711797D02*
G02X141106I2011J0D01*
G01Y708596D01*
G02X137084Y708597I-2011J1D01*
G01Y711797D01*
G37*
G36*
G01X142184Y721846D02*
G02X147006I2411J0D01*
G01Y717445D01*
G02X142184Y717446I-2411J1D01*
G01Y721846D01*
G37*
G36*
G01X180000Y642918D02*
G02Y638894I0J-2012D01*
G01X176799D01*
G02X176800Y642918I1J2012D01*
G01X180000D01*
G37*
G36*
G01X137084Y692899D02*
G02X141106I2011J0D01*
G01Y689698D01*
G02X137084Y689699I-2011J1D01*
G01Y692899D01*
G37*
G36*
G01Y674002D02*
G02X141106I2011J0D01*
G01Y670801D01*
G02X137084Y670802I-2011J1D01*
G01Y674002D01*
G37*
G36*
G01X142184Y702948D02*
G02X147006I2411J0D01*
G01Y698547D01*
G02X142184Y698548I-2411J1D01*
G01Y702948D01*
G37*
G36*
G01Y684050D02*
G02X147006I2411J0D01*
G01Y679649D01*
G02X142184Y679650I-2411J1D01*
G01Y684050D01*
G37*
G36*
G01X137084Y623608D02*
G02X141106I2011J0D01*
G01Y620407D01*
G02X137084Y620408I-2011J1D01*
G01Y623608D01*
G37*
G36*
G01X142184Y633657D02*
G02X147006I2411J0D01*
G01Y629256D01*
G02X142184Y629257I-2411J1D01*
G01Y633657D01*
G37*
G36*
G01X121988Y537073D02*
G02X126012I2012J0D01*
G01Y533872D01*
G02X121988Y533873I-2012J1D01*
G01Y537073D01*
G37*
G36*
G01X137084Y306285D02*
G02X141106I2011J0D01*
G01Y303084D01*
G02X137084Y303085I-2011J1D01*
G01Y306285D01*
G37*
G36*
G01Y287387D02*
G02X141106I2011J0D01*
G01Y284186D01*
G02X137084Y284187I-2011J1D01*
G01Y287387D01*
G37*
G36*
G01X142184Y278538D02*
G02X147006I2411J0D01*
G01Y274137D01*
G02X142184Y274138I-2411J1D01*
G01Y278538D01*
G37*
G36*
G01Y297436D02*
G02X147006I2411J0D01*
G01Y293035D01*
G02X142184Y293036I-2411J1D01*
G01Y297436D01*
G37*
G36*
G01Y316334D02*
G02X147006I2411J0D01*
G01Y311933D01*
G02X142184Y311934I-2411J1D01*
G01Y316334D01*
G37*
G36*
G01X180000Y237406D02*
G02Y233382I0J-2012D01*
G01X176799D01*
G02X176800Y237406I1J2012D01*
G01X180000D01*
G37*
G36*
G01X137084Y268490D02*
G02X141106I2011J0D01*
G01Y265289D01*
G02X137084Y265290I-2011J1D01*
G01Y268490D01*
G37*
G36*
G01Y218096D02*
G02X141106I2011J0D01*
G01Y214895D01*
G02X137084Y214896I-2011J1D01*
G01Y218096D01*
G37*
G36*
G01X142184Y228145D02*
G02X147006I2411J0D01*
G01Y223744D01*
G02X142184Y223745I-2411J1D01*
G01Y228145D01*
G37*
G36*
G01X121988Y131559D02*
G02X126012I2012J0D01*
G01Y128358D01*
G02X121988Y128359I-2012J1D01*
G01Y131559D01*
G37*
G36*
G01X97088Y1768381D02*
G02X101912I2412J0D01*
G01Y1763980D01*
G02X97088Y1763981I-2412J1D01*
G01Y1768381D01*
G37*
G36*
G01X102988Y1726836D02*
G02X107012I2012J0D01*
G01Y1723635D01*
G02X102988Y1723636I-2012J1D01*
G01Y1726836D01*
G37*
G36*
G01Y1777230D02*
G02X107012I2012J0D01*
G01Y1774029D01*
G02X102988Y1774030I-2012J1D01*
G01Y1777230D01*
G37*
G36*
G01X70012Y1750407D02*
G02X65988I-2012J0D01*
G01Y1753608D01*
G02X70012Y1753607I2012J-1D01*
G01Y1750407D01*
G37*
G36*
G01X97088Y1699090D02*
G02X101912I2412J0D01*
G01Y1694689D01*
G02X97088Y1694690I-2412J1D01*
G01Y1699090D01*
G37*
G36*
G01Y1680192D02*
G02X101912I2412J0D01*
G01Y1675791D01*
G02X97088Y1675792I-2412J1D01*
G01Y1680192D01*
G37*
G36*
G01X102988Y1707939D02*
G02X107012I2012J0D01*
G01Y1704738D01*
G02X102988Y1704739I-2012J1D01*
G01Y1707939D01*
G37*
G36*
G01Y1689041D02*
G02X107012I2012J0D01*
G01Y1685840D01*
G02X102988Y1685841I-2012J1D01*
G01Y1689041D01*
G37*
G36*
G01X97088Y1717988D02*
G02X101912I2412J0D01*
G01Y1713587D01*
G02X97088Y1713588I-2412J1D01*
G01Y1717988D01*
G37*
G36*
G01X107012Y1368518D02*
G02X102988I-2012J0D01*
G01Y1371719D01*
G02X107012Y1371718I2012J-1D01*
G01Y1368518D01*
G37*
G36*
G01X101912Y1289178D02*
G02X97088I-2412J0D01*
G01Y1293579D01*
G02X101912Y1293578I2412J-1D01*
G01Y1289178D01*
G37*
G36*
G01X97088Y1362869D02*
G02X101912I2412J0D01*
G01Y1358468D01*
G02X97088Y1358469I-2412J1D01*
G01Y1362869D01*
G37*
G36*
G01X101912Y1308076D02*
G02X97088I-2412J0D01*
G01Y1312477D01*
G02X101912Y1312476I2412J-1D01*
G01Y1308076D01*
G37*
G36*
G01X70012Y1344895D02*
G02X65988I-2012J0D01*
G01Y1348096D01*
G02X70012Y1348095I2012J-1D01*
G01Y1344895D01*
G37*
G36*
G01X107012Y1318124D02*
G02X102988I-2012J0D01*
G01Y1321325D01*
G02X107012Y1321324I2012J-1D01*
G01Y1318124D01*
G37*
G36*
G01Y1299227D02*
G02X102988I-2012J0D01*
G01Y1302428D01*
G02X107012Y1302427I2012J-1D01*
G01Y1299227D01*
G37*
G36*
G01X101912Y1270280D02*
G02X97088I-2412J0D01*
G01Y1274681D01*
G02X101912Y1274680I2412J-1D01*
G01Y1270280D01*
G37*
G36*
G01X107012Y1280329D02*
G02X102988I-2012J0D01*
G01Y1283530D01*
G02X107012Y1283529I2012J-1D01*
G01Y1280329D01*
G37*
G36*
G01X70012Y939383D02*
G02X65988I-2012J0D01*
G01Y942584D01*
G02X70012Y942583I2012J-1D01*
G01Y939383D01*
G37*
G36*
G01X107012Y963006D02*
G02X102988I-2012J0D01*
G01Y966207D01*
G02X107012Y966206I2012J-1D01*
G01Y963006D01*
G37*
G36*
G01X101912Y952957D02*
G02X97088I-2412J0D01*
G01Y957358D01*
G02X101912Y957357I2412J-1D01*
G01Y952957D01*
G37*
G36*
G01X97088Y869168D02*
G02X101912I2412J0D01*
G01Y864767D01*
G02X97088Y864768I-2412J1D01*
G01Y869168D01*
G37*
G36*
G01X107012Y912612D02*
G02X102988I-2012J0D01*
G01Y915813D01*
G02X107012Y915812I2012J-1D01*
G01Y912612D01*
G37*
G36*
G01Y893715D02*
G02X102988I-2012J0D01*
G01Y896916D01*
G02X107012Y896915I2012J-1D01*
G01Y893715D01*
G37*
G36*
G01Y874817D02*
G02X102988I-2012J0D01*
G01Y878018D01*
G02X107012Y878017I2012J-1D01*
G01Y874817D01*
G37*
G36*
G01X101912Y902564D02*
G02X97088I-2412J0D01*
G01Y906965D01*
G02X101912Y906964I2412J-1D01*
G01Y902564D01*
G37*
G36*
G01Y883666D02*
G02X97088I-2412J0D01*
G01Y888067D01*
G02X101912Y888066I2412J-1D01*
G01Y883666D01*
G37*
G36*
G01X97088Y551845D02*
G02X101912I2412J0D01*
G01Y547444D01*
G02X97088Y547445I-2412J1D01*
G01Y551845D01*
G37*
G36*
G01X70012Y533871D02*
G02X65988I-2012J0D01*
G01Y537072D01*
G02X70012Y537071I2012J-1D01*
G01Y533871D01*
G37*
G36*
G01X107012Y507100D02*
G02X102988I-2012J0D01*
G01Y510301D01*
G02X107012Y510300I2012J-1D01*
G01Y507100D01*
G37*
G36*
G01Y557494D02*
G02X102988I-2012J0D01*
G01Y560695D01*
G02X107012Y560694I2012J-1D01*
G01Y557494D01*
G37*
G36*
G01Y488203D02*
G02X102988I-2012J0D01*
G01Y491404D01*
G02X107012Y491403I2012J-1D01*
G01Y488203D01*
G37*
G36*
G01X101912Y497052D02*
G02X97088I-2412J0D01*
G01Y501453D01*
G02X101912Y501452I2412J-1D01*
G01Y497052D01*
G37*
G36*
G01X107012Y469305D02*
G02X102988I-2012J0D01*
G01Y472506D01*
G02X107012Y472505I2012J-1D01*
G01Y469305D01*
G37*
G36*
G01X97088Y463656D02*
G02X101912I2412J0D01*
G01Y459255D01*
G02X97088Y459256I-2412J1D01*
G01Y463656D01*
G37*
G36*
G01X101912Y478154D02*
G02X97088I-2412J0D01*
G01Y482555D01*
G02X101912Y482554I2412J-1D01*
G01Y478154D01*
G37*
G36*
G01X65988Y131559D02*
G02X70012I2012J0D01*
G01Y128358D01*
G02X65988Y128359I-2012J1D01*
G01Y131559D01*
G37*
G36*
G01X107012Y151982D02*
G02X102988I-2012J0D01*
G01Y155183D01*
G02X107012Y155182I2012J-1D01*
G01Y151982D01*
G37*
G36*
G01X101912Y141933D02*
G02X97088I-2412J0D01*
G01Y146334D01*
G02X101912Y146333I2412J-1D01*
G01Y141933D01*
G37*
G36*
G01Y72642D02*
G02X97088I-2412J0D01*
G01Y77043D01*
G02X101912Y77042I2412J-1D01*
G01Y72642D01*
G37*
G36*
G01X97088Y58244D02*
G02X101912I2412J0D01*
G01Y53843D01*
G02X97088Y53844I-2412J1D01*
G01Y58244D01*
G37*
G36*
G01X107012Y101588D02*
G02X102988I-2012J0D01*
G01Y104789D01*
G02X107012Y104788I2012J-1D01*
G01Y101588D01*
G37*
G36*
G01Y82691D02*
G02X102988I-2012J0D01*
G01Y85892D01*
G02X107012Y85891I2012J-1D01*
G01Y82691D01*
G37*
G36*
G01Y63793D02*
G02X102988I-2012J0D01*
G01Y66994D01*
G02X107012Y66993I2012J-1D01*
G01Y63793D01*
G37*
G36*
G01X101912Y91540D02*
G02X97088I-2412J0D01*
G01Y95941D01*
G02X101912Y95940I2412J-1D01*
G01Y91540D01*
G37*
G36*
G01X29562Y1922835D02*
Y1920190D01*
G03X30865Y1916500I5874J-1D01*
G02X12442I-9211J-7446D01*
G03X13746Y1920190I-4571J3691D01*
G01Y1922835D01*
G02X29562I7908J0D01*
G37*
G36*
G01X28700Y1771570D02*
G02Y1767546I0J-2012D01*
G01X25499D01*
G02X25500Y1771570I1J2012D01*
G01X28700D01*
G37*
G36*
G01X29540Y1732221D02*
G02X25518I-2011J0D01*
G01Y1735422D01*
G02X29540Y1735421I2011J-1D01*
G01Y1732221D01*
G37*
G36*
G01Y1744820D02*
G02X25518I-2011J0D01*
G01Y1748021D01*
G02X29540Y1748020I2011J-1D01*
G01Y1744820D01*
G37*
G36*
G01Y1757418D02*
G02X25518I-2011J0D01*
G01Y1760619D01*
G02X29540Y1760618I2011J-1D01*
G01Y1757418D01*
G37*
G36*
G01X22012Y1725729D02*
G02X17988I-2012J0D01*
G01Y1728930D01*
G02X22012Y1728929I2012J-1D01*
G01Y1725729D01*
G37*
G36*
G01Y1738328D02*
G02X17988I-2012J0D01*
G01Y1741529D01*
G02X22012Y1741528I2012J-1D01*
G01Y1738328D01*
G37*
G36*
G01Y1750926D02*
G02X17988I-2012J0D01*
G01Y1754127D01*
G02X22012Y1754126I2012J-1D01*
G01Y1750926D01*
G37*
G36*
G01X25518Y1688177D02*
G02X29540I2011J0D01*
G01Y1684976D01*
G02X25518Y1684977I-2011J1D01*
G01Y1688177D01*
G37*
G36*
G01Y1700776D02*
G02X29540I2011J0D01*
G01Y1697575D01*
G02X25518Y1697576I-2011J1D01*
G01Y1700776D01*
G37*
G36*
G01Y1675579D02*
G02X29540I2011J0D01*
G01Y1672378D01*
G02X25518Y1672379I-2011J1D01*
G01Y1675579D01*
G37*
G36*
G01X29540Y1719623D02*
G02X25518I-2011J0D01*
G01Y1722824D01*
G02X29540Y1722823I2011J-1D01*
G01Y1719623D01*
G37*
G36*
G01X17988Y1669087D02*
G02X22012I2012J0D01*
G01Y1665886D01*
G02X17988Y1665887I-2012J1D01*
G01Y1669087D01*
G37*
G36*
G01Y1681685D02*
G02X22012I2012J0D01*
G01Y1678484D01*
G02X17988Y1678485I-2012J1D01*
G01Y1681685D01*
G37*
G36*
G01Y1694283D02*
G02X22012I2012J0D01*
G01Y1691082D01*
G02X17988Y1691083I-2012J1D01*
G01Y1694283D01*
G37*
G36*
G01X22012Y1713131D02*
G02X17988I-2012J0D01*
G01Y1716332D01*
G02X22012Y1716331I2012J-1D01*
G01Y1713131D01*
G37*
G36*
G01X29540Y1583999D02*
G02X25518I-2011J0D01*
G01Y1587200D01*
G02X29540Y1587199I2011J-1D01*
G01Y1583999D01*
G37*
G36*
G01Y1596597D02*
G02X25518I-2011J0D01*
G01Y1599798D01*
G02X29540Y1599797I2011J-1D01*
G01Y1596597D01*
G37*
G36*
G01Y1609196D02*
G02X25518I-2011J0D01*
G01Y1612397D01*
G02X29540Y1612396I2011J-1D01*
G01Y1609196D01*
G37*
G36*
G01Y1621794D02*
G02X25518I-2011J0D01*
G01Y1624995D01*
G02X29540Y1624994I2011J-1D01*
G01Y1621794D01*
G37*
G36*
G01X25518Y1637593D02*
G02X29540I2011J0D01*
G01Y1634392D01*
G02X25518Y1634393I-2011J1D01*
G01Y1637593D01*
G37*
G36*
G01X22012Y1590296D02*
G02X17988I-2012J0D01*
G01Y1593497D01*
G02X22012Y1593496I2012J-1D01*
G01Y1590296D01*
G37*
G36*
G01Y1602894D02*
G02X17988I-2012J0D01*
G01Y1606095D01*
G02X22012Y1606094I2012J-1D01*
G01Y1602894D01*
G37*
G36*
G01Y1615493D02*
G02X17988I-2012J0D01*
G01Y1618694D01*
G02X22012Y1618693I2012J-1D01*
G01Y1615493D01*
G37*
G36*
G01Y1628091D02*
G02X17988I-2012J0D01*
G01Y1631292D01*
G02X22012Y1631291I2012J-1D01*
G01Y1628091D01*
G37*
G36*
G01X17988Y1643890D02*
G02X22012I2012J0D01*
G01Y1640689D01*
G02X17988Y1640690I-2012J1D01*
G01Y1643890D01*
G37*
G36*
G01X33001Y1516112D02*
G02Y1520134I0J2011D01*
G01X36202D01*
G02X36201Y1516112I-1J-2011D01*
G01X33001D01*
G37*
G36*
G01X25518Y1527356D02*
G02X29540I2011J0D01*
G01Y1524155D01*
G02X25518Y1524156I-2011J1D01*
G01Y1527356D01*
G37*
G36*
G01Y1539955D02*
G02X29540I2011J0D01*
G01Y1536754D01*
G02X25518Y1536755I-2011J1D01*
G01Y1539955D01*
G37*
G36*
G01Y1552553D02*
G02X29540I2011J0D01*
G01Y1549352D01*
G02X25518Y1549353I-2011J1D01*
G01Y1552553D01*
G37*
G36*
G01Y1565152D02*
G02X29540I2011J0D01*
G01Y1561951D01*
G02X25518Y1561952I-2011J1D01*
G01Y1565152D01*
G37*
G36*
G01X17988Y1533654D02*
G02X22012I2012J0D01*
G01Y1530453D01*
G02X17988Y1530454I-2012J1D01*
G01Y1533654D01*
G37*
G36*
G01Y1546252D02*
G02X22012I2012J0D01*
G01Y1543051D01*
G02X17988Y1543052I-2012J1D01*
G01Y1546252D01*
G37*
G36*
G01Y1558850D02*
G02X22012I2012J0D01*
G01Y1555649D01*
G02X17988Y1555650I-2012J1D01*
G01Y1558850D01*
G37*
G36*
G01Y1571449D02*
G02X22012I2012J0D01*
G01Y1568248D01*
G02X17988Y1568249I-2012J1D01*
G01Y1571449D01*
G37*
G36*
G01X29540Y1365102D02*
G02X25518I-2011J0D01*
G01Y1368303D01*
G02X29540Y1368302I2011J-1D01*
G01Y1365102D01*
G37*
G36*
G01Y1377700D02*
G02X25518I-2011J0D01*
G01Y1380901D01*
G02X29540Y1380900I2011J-1D01*
G01Y1377700D01*
G37*
G36*
G01X25518Y1393499D02*
G02X29540I2011J0D01*
G01Y1390298D01*
G02X25518Y1390299I-2011J1D01*
G01Y1393499D01*
G37*
G36*
G01X29540Y1402897D02*
G02X25518I-2011J0D01*
G01Y1406098D01*
G02X29540Y1406097I2011J-1D01*
G01Y1402897D01*
G37*
G36*
G01X17988Y1374599D02*
G02X22012I2012J0D01*
G01Y1371398D01*
G02X17988Y1371399I-2012J1D01*
G01Y1374599D01*
G37*
G36*
G01Y1387198D02*
G02X22012I2012J0D01*
G01Y1383997D01*
G02X17988Y1383998I-2012J1D01*
G01Y1387198D01*
G37*
G36*
G01Y1399796D02*
G02X22012I2012J0D01*
G01Y1396595D01*
G02X17988Y1396596I-2012J1D01*
G01Y1399796D01*
G37*
G36*
G01Y1412395D02*
G02X22012I2012J0D01*
G01Y1409194D01*
G02X17988Y1409195I-2012J1D01*
G01Y1412395D01*
G37*
G36*
G01X29540Y1292661D02*
G02X25518I-2011J0D01*
G01Y1295862D01*
G02X29540Y1295861I2011J-1D01*
G01Y1292661D01*
G37*
G36*
G01X25518Y1318108D02*
G02X29540I2011J0D01*
G01Y1314907D01*
G02X25518Y1314908I-2011J1D01*
G01Y1318108D01*
G37*
G36*
G01Y1330707D02*
G02X29540I2011J0D01*
G01Y1327506D01*
G02X25518Y1327507I-2011J1D01*
G01Y1330707D01*
G37*
G36*
G01Y1343305D02*
G02X29540I2011J0D01*
G01Y1340104D01*
G02X25518Y1340105I-2011J1D01*
G01Y1343305D01*
G37*
G36*
G01Y1355904D02*
G02X29540I2011J0D01*
G01Y1352703D01*
G02X25518Y1352704I-2011J1D01*
G01Y1355904D01*
G37*
G36*
G01X17988Y1362001D02*
G02X22012I2012J0D01*
G01Y1358800D01*
G02X17988Y1358801I-2012J1D01*
G01Y1362001D01*
G37*
G36*
G01Y1349402D02*
G02X22012I2012J0D01*
G01Y1346201D01*
G02X17988Y1346202I-2012J1D01*
G01Y1349402D01*
G37*
G36*
G01Y1336804D02*
G02X22012I2012J0D01*
G01Y1333603D01*
G02X17988Y1333604I-2012J1D01*
G01Y1336804D01*
G37*
G36*
G01Y1324206D02*
G02X22012I2012J0D01*
G01Y1321005D01*
G02X17988Y1321006I-2012J1D01*
G01Y1324206D01*
G37*
G36*
G01Y1302158D02*
G02X22012I2012J0D01*
G01Y1298957D01*
G02X17988Y1298958I-2012J1D01*
G01Y1302158D01*
G37*
G36*
G01Y1289560D02*
G02X22012I2012J0D01*
G01Y1286359D01*
G02X17988Y1286360I-2012J1D01*
G01Y1289560D01*
G37*
G36*
G01X29540Y1280063D02*
G02X25518I-2011J0D01*
G01Y1283264D01*
G02X29540Y1283263I2011J-1D01*
G01Y1280063D01*
G37*
G36*
G01Y1267464D02*
G02X25518I-2011J0D01*
G01Y1270665D01*
G02X29540Y1270664I2011J-1D01*
G01Y1267464D01*
G37*
G36*
G01Y1254866D02*
G02X25518I-2011J0D01*
G01Y1258067D01*
G02X29540Y1258066I2011J-1D01*
G01Y1254866D01*
G37*
G36*
G01Y1223370D02*
G02X25518I-2011J0D01*
G01Y1226571D01*
G02X29540Y1226570I2011J-1D01*
G01Y1223370D01*
G37*
G36*
G01X17988Y1276961D02*
G02X22012I2012J0D01*
G01Y1273760D01*
G02X17988Y1273761I-2012J1D01*
G01Y1276961D01*
G37*
G36*
G01Y1264363D02*
G02X22012I2012J0D01*
G01Y1261162D01*
G02X17988Y1261163I-2012J1D01*
G01Y1264363D01*
G37*
G36*
G01Y1251765D02*
G02X22012I2012J0D01*
G01Y1248564D01*
G02X17988Y1248565I-2012J1D01*
G01Y1251765D01*
G37*
G36*
G01Y1220269D02*
G02X22012I2012J0D01*
G01Y1217068D01*
G02X17988Y1217069I-2012J1D01*
G01Y1220269D01*
G37*
G36*
G01X29540Y1210771D02*
G02X25518I-2011J0D01*
G01Y1213972D01*
G02X29540Y1213971I2011J-1D01*
G01Y1210771D01*
G37*
G36*
G01Y1198173D02*
G02X25518I-2011J0D01*
G01Y1201374D01*
G02X29540Y1201373I2011J-1D01*
G01Y1198173D01*
G37*
G36*
G01Y1185574D02*
G02X25518I-2011J0D01*
G01Y1188775D01*
G02X29540Y1188774I2011J-1D01*
G01Y1185574D01*
G37*
G36*
G01Y1172976D02*
G02X25518I-2011J0D01*
G01Y1176177D01*
G02X29540Y1176176I2011J-1D01*
G01Y1172976D01*
G37*
G36*
G01Y1160378D02*
G02X25518I-2011J0D01*
G01Y1163579D01*
G02X29540Y1163578I2011J-1D01*
G01Y1160378D01*
G37*
G36*
G01Y1147779D02*
G02X25518I-2011J0D01*
G01Y1150980D01*
G02X29540Y1150979I2011J-1D01*
G01Y1147779D01*
G37*
G36*
G01X17988Y1195072D02*
G02X22012I2012J0D01*
G01Y1191871D01*
G02X17988Y1191872I-2012J1D01*
G01Y1195072D01*
G37*
G36*
G01Y1207670D02*
G02X22012I2012J0D01*
G01Y1204469D01*
G02X17988Y1204470I-2012J1D01*
G01Y1207670D01*
G37*
G36*
G01Y1182473D02*
G02X22012I2012J0D01*
G01Y1179272D01*
G02X17988Y1179273I-2012J1D01*
G01Y1182473D01*
G37*
G36*
G01Y1169875D02*
G02X22012I2012J0D01*
G01Y1166674D01*
G02X17988Y1166675I-2012J1D01*
G01Y1169875D01*
G37*
G36*
G01Y1157276D02*
G02X22012I2012J0D01*
G01Y1154075D01*
G02X17988Y1154076I-2012J1D01*
G01Y1157276D01*
G37*
G36*
G01Y1144678D02*
G02X22012I2012J0D01*
G01Y1141477D01*
G02X17988Y1141478I-2012J1D01*
G01Y1144678D01*
G37*
G36*
G01X25518Y1113384D02*
G02X29540I2011J0D01*
G01Y1110183D01*
G02X25518Y1110184I-2011J1D01*
G01Y1113384D01*
G37*
G36*
G01Y1138381D02*
G02X29540I2011J0D01*
G01Y1135180D01*
G02X25518Y1135181I-2011J1D01*
G01Y1138381D01*
G37*
G36*
G01Y1100785D02*
G02X29540I2011J0D01*
G01Y1097584D01*
G02X25518Y1097585I-2011J1D01*
G01Y1100785D01*
G37*
G36*
G01X17988Y1119481D02*
G02X22012I2012J0D01*
G01Y1116280D01*
G02X17988Y1116281I-2012J1D01*
G01Y1119481D01*
G37*
G36*
G01Y1106883D02*
G02X22012I2012J0D01*
G01Y1103682D01*
G02X17988Y1103683I-2012J1D01*
G01Y1106883D01*
G37*
G36*
G01X25518Y859441D02*
G02X29540I2011J0D01*
G01Y856240D01*
G02X25518Y856241I-2011J1D01*
G01Y859441D01*
G37*
G36*
G01X29540Y868839D02*
G02X25518I-2011J0D01*
G01Y872040D01*
G02X29540Y872039I2011J-1D01*
G01Y868839D01*
G37*
G36*
G01X25518Y884687D02*
G02X29540I2011J0D01*
G01Y881486D01*
G02X25518Y881487I-2011J1D01*
G01Y884687D01*
G37*
G36*
G01Y910034D02*
G02X29540I2011J0D01*
G01Y906833D01*
G02X25518Y906834I-2011J1D01*
G01Y910034D01*
G37*
G36*
G01Y897436D02*
G02X29540I2011J0D01*
G01Y894235D01*
G02X25518Y894236I-2011J1D01*
G01Y897436D01*
G37*
G36*
G01X17988Y853339D02*
G02X22012I2012J0D01*
G01Y850138D01*
G02X17988Y850139I-2012J1D01*
G01Y853339D01*
G37*
G36*
G01Y865938D02*
G02X22012I2012J0D01*
G01Y862737D01*
G02X17988Y862738I-2012J1D01*
G01Y865938D01*
G37*
G36*
G01Y878536D02*
G02X22012I2012J0D01*
G01Y875335D01*
G02X17988Y875336I-2012J1D01*
G01Y878536D01*
G37*
G36*
G01Y903733D02*
G02X22012I2012J0D01*
G01Y900532D01*
G02X17988Y900533I-2012J1D01*
G01Y903733D01*
G37*
G36*
G01Y916332D02*
G02X22012I2012J0D01*
G01Y913131D01*
G02X17988Y913132I-2012J1D01*
G01Y916332D01*
G37*
G36*
G01X25518Y846842D02*
G02X29540I2011J0D01*
G01Y843641D01*
G02X25518Y843642I-2011J1D01*
G01Y846842D01*
G37*
G36*
G01Y834444D02*
G02X29540I2011J0D01*
G01Y831243D01*
G02X25518Y831244I-2011J1D01*
G01Y834444D01*
G37*
G36*
G01Y821845D02*
G02X29540I2011J0D01*
G01Y818644D01*
G02X25518Y818645I-2011J1D01*
G01Y821845D01*
G37*
G36*
G01Y809247D02*
G02X29540I2011J0D01*
G01Y806046D01*
G02X25518Y806047I-2011J1D01*
G01Y809247D01*
G37*
G36*
G01Y796648D02*
G02X29540I2011J0D01*
G01Y793447D01*
G02X25518Y793448I-2011J1D01*
G01Y796648D01*
G37*
G36*
G01X17988Y790347D02*
G02X22012I2012J0D01*
G01Y787146D01*
G02X17988Y787147I-2012J1D01*
G01Y790347D01*
G37*
G36*
G01Y802946D02*
G02X22012I2012J0D01*
G01Y799745D01*
G02X17988Y799746I-2012J1D01*
G01Y802946D01*
G37*
G36*
G01Y815544D02*
G02X22012I2012J0D01*
G01Y812343D01*
G02X17988Y812344I-2012J1D01*
G01Y815544D01*
G37*
G36*
G01Y828143D02*
G02X22012I2012J0D01*
G01Y824942D01*
G02X17988Y824943I-2012J1D01*
G01Y828143D01*
G37*
G36*
G01Y840741D02*
G02X22012I2012J0D01*
G01Y837540D01*
G02X17988Y837541I-2012J1D01*
G01Y840741D01*
G37*
G36*
G01X25518Y774601D02*
G02X29540I2011J0D01*
G01Y771400D01*
G02X25518Y771401I-2011J1D01*
G01Y774601D01*
G37*
G36*
G01Y762003D02*
G02X29540I2011J0D01*
G01Y758802D01*
G02X25518Y758803I-2011J1D01*
G01Y762003D01*
G37*
G36*
G01Y730507D02*
G02X29540I2011J0D01*
G01Y727306D01*
G02X25518Y727307I-2011J1D01*
G01Y730507D01*
G37*
G36*
G01Y717908D02*
G02X29540I2011J0D01*
G01Y714707D01*
G02X25518Y714708I-2011J1D01*
G01Y717908D01*
G37*
G36*
G01X17988Y768300D02*
G02X22012I2012J0D01*
G01Y765099D01*
G02X17988Y765100I-2012J1D01*
G01Y768300D01*
G37*
G36*
G01Y755702D02*
G02X22012I2012J0D01*
G01Y752501D01*
G02X17988Y752502I-2012J1D01*
G01Y755702D01*
G37*
G36*
G01Y724206D02*
G02X22012I2012J0D01*
G01Y721005D01*
G02X17988Y721006I-2012J1D01*
G01Y724206D01*
G37*
G36*
G01Y711607D02*
G02X22012I2012J0D01*
G01Y708406D01*
G02X17988Y708407I-2012J1D01*
G01Y711607D01*
G37*
G36*
G01Y636017D02*
G02X22012I2012J0D01*
G01Y632816D01*
G02X17988Y632817I-2012J1D01*
G01Y636017D01*
G37*
G36*
G01Y699009D02*
G02X22012I2012J0D01*
G01Y695808D01*
G02X17988Y695809I-2012J1D01*
G01Y699009D01*
G37*
G36*
G01X25518Y642518D02*
G02X29540I2011J0D01*
G01Y639317D01*
G02X25518Y639318I-2011J1D01*
G01Y642518D01*
G37*
G36*
G01Y667715D02*
G02X29540I2011J0D01*
G01Y664514D01*
G02X25518Y664515I-2011J1D01*
G01Y667715D01*
G37*
G36*
G01Y680313D02*
G02X29540I2011J0D01*
G01Y677112D01*
G02X25518Y677113I-2011J1D01*
G01Y680313D01*
G37*
G36*
G01Y692911D02*
G02X29540I2011J0D01*
G01Y689710D01*
G02X25518Y689711I-2011J1D01*
G01Y692911D01*
G37*
G36*
G01Y705510D02*
G02X29540I2011J0D01*
G01Y702309D01*
G02X25518Y702310I-2011J1D01*
G01Y705510D01*
G37*
G36*
G01X17988Y686410D02*
G02X22012I2012J0D01*
G01Y683209D01*
G02X17988Y683210I-2012J1D01*
G01Y686410D01*
G37*
G36*
G01Y673812D02*
G02X22012I2012J0D01*
G01Y670611D01*
G02X17988Y670612I-2012J1D01*
G01Y673812D01*
G37*
G36*
G01Y661213D02*
G02X22012I2012J0D01*
G01Y658012D01*
G02X17988Y658013I-2012J1D01*
G01Y661213D01*
G37*
G36*
G01Y648615D02*
G02X22012I2012J0D01*
G01Y645414D01*
G02X17988Y645415I-2012J1D01*
G01Y648615D01*
G37*
G36*
G01X25518Y617271D02*
G02X29540I2011J0D01*
G01Y614070D01*
G02X25518Y614071I-2011J1D01*
G01Y617271D01*
G37*
G36*
G01Y604722D02*
G02X29540I2011J0D01*
G01Y601521D01*
G02X25518Y601522I-2011J1D01*
G01Y604722D01*
G37*
G36*
G01Y629919D02*
G02X29540I2011J0D01*
G01Y626718D01*
G02X25518Y626719I-2011J1D01*
G01Y629919D01*
G37*
G36*
G01X17988Y623418D02*
G02X22012I2012J0D01*
G01Y620217D01*
G02X17988Y620218I-2012J1D01*
G01Y623418D01*
G37*
G36*
G01Y610820D02*
G02X22012I2012J0D01*
G01Y607619D01*
G02X17988Y607620I-2012J1D01*
G01Y610820D01*
G37*
G36*
G01X41372Y281496D02*
Y278851D01*
G03X42676Y275161I5875J1D01*
G02X24253I-9212J-7446D01*
G03X25556Y278851I-4571J3689D01*
G01Y281496D01*
G02X41372I7908J0D01*
G37*
G54D34*
X82087Y28858D03*
Y178464D03*
Y434370D03*
Y583976D03*
Y839882D03*
Y989488D03*
Y1245394D03*
Y1395000D03*
Y1650906D03*
Y1800512D03*
X162008Y191614D03*
Y341220D03*
Y597126D03*
Y746732D03*
Y1002638D03*
Y1152244D03*
Y1408150D03*
Y1557756D03*
Y1813662D03*
Y1963268D03*
X890354Y191614D03*
Y341220D03*
Y597126D03*
Y746732D03*
Y1002638D03*
Y1152244D03*
Y1408150D03*
Y1557756D03*
Y1813662D03*
Y1963268D03*
G54D33*
X25499Y1950499D03*
X1010999Y43999D03*
X1010499Y1950499D03*
G54D31*
X11811Y571426D03*
Y949378D03*
Y1067489D03*
Y1484811D03*
Y1445441D03*
Y1862763D03*
G54D35*
X1023228Y1416024D03*
Y1694212D03*
G54D32*
X33469Y1029523D03*
X269690Y1490152D03*
G54D22*
X72835Y17047D03*
Y190275D03*
Y422559D03*
Y595787D03*
Y828071D03*
Y1001299D03*
Y1233583D03*
Y1406811D03*
Y1639095D03*
Y1812323D03*
X171260Y179803D03*
Y353031D03*
Y585315D03*
Y758543D03*
Y990827D03*
Y1164055D03*
Y1396339D03*
Y1569567D03*
Y1801851D03*
Y1975079D03*
X899606Y179803D03*
Y353031D03*
Y585315D03*
Y758543D03*
Y990827D03*
Y1164055D03*
Y1396339D03*
Y1569567D03*
Y1801851D03*
Y1975079D03*
G54D16*
X20000Y607620D03*
Y610820D03*
Y620218D03*
Y623418D03*
X27529Y601522D03*
Y604722D03*
Y614071D03*
Y617271D03*
Y626719D03*
Y629919D03*
X20000Y658013D03*
Y661213D03*
Y670612D03*
Y673812D03*
Y683210D03*
Y686410D03*
Y632817D03*
Y636017D03*
Y695809D03*
Y699009D03*
Y645415D03*
Y648615D03*
X27529Y664515D03*
Y667715D03*
Y677113D03*
Y680313D03*
Y689711D03*
Y692911D03*
Y702310D03*
Y639318D03*
Y642518D03*
X20000Y708407D03*
Y711607D03*
Y721006D03*
Y724206D03*
Y752502D03*
Y755702D03*
Y765100D03*
Y768300D03*
X27529Y714708D03*
Y717908D03*
Y727307D03*
Y730507D03*
Y758803D03*
Y762003D03*
Y705510D03*
Y771401D03*
Y774601D03*
X27699Y737535D03*
X20000Y837541D03*
Y840741D03*
Y787147D03*
Y790347D03*
Y799746D03*
Y802946D03*
Y812344D03*
Y815544D03*
Y824943D03*
Y828143D03*
X27529Y843642D03*
Y846842D03*
Y793448D03*
Y796648D03*
Y806047D03*
Y809247D03*
Y818645D03*
Y821845D03*
Y831244D03*
Y834444D03*
X20000Y900533D03*
Y903733D03*
Y850139D03*
Y853339D03*
Y913132D03*
Y916332D03*
Y862738D03*
Y865938D03*
Y875336D03*
Y878536D03*
X27529Y894236D03*
Y897436D03*
Y856241D03*
Y859441D03*
Y906834D03*
Y910034D03*
Y868839D03*
Y872039D03*
Y881487D03*
Y884687D03*
X34872Y890906D03*
X30000Y991000D03*
X23291Y1062791D03*
X20000Y1103683D03*
Y1106883D03*
Y1116281D03*
Y1119481D03*
X27529Y1135181D03*
Y1138381D03*
Y1097585D03*
Y1100785D03*
Y1110184D03*
Y1113384D03*
X32335Y1122002D03*
X37396Y1130912D03*
X33971Y1131741D03*
X20000Y1141478D03*
Y1144678D03*
Y1191872D03*
Y1195072D03*
Y1154076D03*
Y1157276D03*
Y1204470D03*
Y1207670D03*
Y1166675D03*
Y1169875D03*
Y1179273D03*
Y1182473D03*
X27529Y1185574D03*
Y1188774D03*
Y1147779D03*
Y1150979D03*
Y1198173D03*
Y1201373D03*
Y1160378D03*
Y1163578D03*
Y1210771D03*
Y1172976D03*
Y1176176D03*
X20000Y1261163D03*
Y1264363D03*
Y1273761D03*
Y1276961D03*
Y1217069D03*
Y1220269D03*
Y1248565D03*
Y1251765D03*
X27529Y1254866D03*
Y1258066D03*
Y1267464D03*
Y1270664D03*
Y1280063D03*
Y1283263D03*
Y1213971D03*
Y1223370D03*
Y1226570D03*
X33201Y1230674D03*
X32959Y1234478D03*
X36000Y1236000D03*
X20000Y1321006D03*
Y1324206D03*
Y1333604D03*
Y1336804D03*
Y1346202D03*
Y1349402D03*
Y1286360D03*
Y1289560D03*
Y1298958D03*
Y1302158D03*
X27529Y1314908D03*
Y1318108D03*
Y1327507D03*
Y1330707D03*
Y1340105D03*
Y1343305D03*
Y1352704D03*
Y1355904D03*
Y1292661D03*
Y1295861D03*
X36170Y1308434D03*
X33699Y1301782D03*
X26500Y1305121D03*
X33938Y1311000D03*
X38500D03*
X30000Y1305000D03*
X30700Y1308600D03*
X20000Y1371399D03*
Y1374599D03*
Y1383998D03*
Y1387198D03*
Y1396596D03*
Y1399796D03*
Y1358801D03*
Y1362001D03*
Y1409195D03*
Y1412395D03*
X27529Y1365102D03*
Y1368302D03*
Y1377700D03*
Y1380900D03*
Y1390299D03*
Y1393499D03*
Y1402897D03*
Y1406097D03*
X27000Y1417500D03*
X32500Y1417600D03*
X28000Y1444000D03*
X20000Y1530454D03*
Y1533654D03*
Y1543052D03*
Y1546252D03*
Y1555650D03*
Y1558850D03*
Y1568249D03*
Y1571449D03*
X27529Y1524156D03*
Y1527356D03*
Y1536755D03*
Y1539955D03*
Y1549353D03*
Y1552553D03*
Y1561952D03*
Y1565152D03*
X33001Y1518123D03*
X36201D03*
X20000Y1640690D03*
Y1643890D03*
Y1593496D03*
Y1590296D03*
Y1606094D03*
Y1602894D03*
Y1618693D03*
Y1615493D03*
Y1631291D03*
Y1628091D03*
X27529Y1634393D03*
Y1637593D03*
Y1587199D03*
Y1583999D03*
Y1599797D03*
Y1596597D03*
Y1612396D03*
Y1609196D03*
Y1624994D03*
Y1621794D03*
X20000Y1716331D03*
Y1713131D03*
Y1665887D03*
Y1669087D03*
Y1678485D03*
Y1681685D03*
Y1691083D03*
Y1694283D03*
X27529Y1719623D03*
Y1672379D03*
Y1675579D03*
Y1684977D03*
Y1688177D03*
Y1697576D03*
Y1700776D03*
X35900Y1706000D03*
X34224Y1709000D03*
X38000Y1715000D03*
X20000Y1728929D03*
Y1725729D03*
Y1741528D03*
Y1738328D03*
Y1754126D03*
Y1750926D03*
X27529Y1722823D03*
Y1735421D03*
Y1732221D03*
Y1748020D03*
Y1744820D03*
Y1760618D03*
Y1757418D03*
X25500Y1769558D03*
X28700D03*
X30200Y1970300D03*
X96000Y119000D03*
X99500Y95940D03*
Y91540D03*
Y77042D03*
Y72642D03*
Y58244D03*
Y53844D03*
X105000Y104788D03*
Y101588D03*
Y85891D03*
Y82691D03*
Y66993D03*
Y63793D03*
X72500Y61161D03*
X71000Y125236D03*
X68000Y128359D03*
Y131559D03*
X99500Y146333D03*
Y141933D03*
X105000Y155182D03*
Y151982D03*
X99300Y201000D03*
X60306Y212338D03*
X80153Y230246D03*
X85427Y239715D03*
X100400Y208300D03*
X70500Y242988D03*
X80300Y234465D03*
X97400Y220200D03*
X66610Y295956D03*
X56024Y292549D03*
X110000Y362500D03*
X106500D03*
X110000Y366000D03*
X106500D03*
X92700Y358400D03*
X52066Y370649D03*
X99500Y482554D03*
Y478154D03*
Y463656D03*
Y459256D03*
X105000Y472505D03*
Y469305D03*
X72500Y466673D03*
X71000Y530748D03*
X96000Y524000D03*
X68000Y533871D03*
Y537071D03*
X99500Y551845D03*
Y547445D03*
Y501452D03*
Y497052D03*
X105000Y557494D03*
Y510300D03*
Y507100D03*
Y491403D03*
Y488203D03*
X71000Y524464D03*
X89400Y603250D03*
X95900Y605500D03*
X62426Y607740D03*
X105000Y560694D03*
X88600Y623300D03*
X80153Y635758D03*
X85223Y645227D03*
X70500Y648500D03*
X48000Y649500D03*
X46500Y653500D03*
X80300Y639977D03*
X50560Y653500D03*
X106500Y771500D03*
X110000D03*
Y768000D03*
X106500D03*
X86900Y774750D03*
X49500Y771000D03*
X80215Y777137D03*
X47500Y901500D03*
X99500Y906964D03*
Y902564D03*
Y888066D03*
Y883666D03*
Y869168D03*
Y864768D03*
X105000Y915812D03*
Y912612D03*
Y896915D03*
Y893715D03*
Y878017D03*
Y874817D03*
X72500Y872185D03*
X96000Y930000D03*
X71000Y936260D03*
X68000Y939383D03*
Y942583D03*
X99500Y957357D03*
Y952957D03*
X105000Y966206D03*
Y963006D03*
X65500Y927500D03*
X71000Y925500D03*
X93000Y1005700D03*
X81689Y1039600D03*
X77750Y1056750D03*
X96500Y1011200D03*
X64037Y1016654D03*
X74000Y1047500D03*
X41000Y1057500D03*
X81689Y1049400D03*
X106100Y1030000D03*
X42286Y1089500D03*
Y1085500D03*
X67090Y1070360D03*
X41608Y1125065D03*
X39959Y1128308D03*
X110000Y1173500D03*
X106500D03*
X110000Y1177000D03*
X106500D03*
X88500Y1177300D03*
X40097Y1142513D03*
X85300Y1182000D03*
X99500Y1274680D03*
Y1270280D03*
X105000Y1283529D03*
Y1280329D03*
X72500Y1277697D03*
X71000Y1341772D03*
X96000Y1335000D03*
X68000Y1344895D03*
Y1348095D03*
X99500Y1312476D03*
Y1308076D03*
Y1293578D03*
Y1289178D03*
X105000Y1321324D03*
Y1318124D03*
Y1302427D03*
Y1299227D03*
X71000Y1335488D03*
X58900Y1317000D03*
X96250Y1414400D03*
X62962Y1422600D03*
X100000Y1423000D03*
X99900Y1419600D03*
X99500Y1362869D03*
Y1358469D03*
X105000Y1371718D03*
Y1368518D03*
X110000Y1470000D03*
X99300Y1431200D03*
X82748Y1455148D03*
X76750Y1462762D03*
X80153Y1446781D03*
X73000Y1455100D03*
X69365Y1474719D03*
X80300Y1451000D03*
X82005Y1540500D03*
X85808D03*
X110500Y1573200D03*
X107000D03*
X103500D03*
X80465Y1570120D03*
X109050Y1540600D03*
X46893Y1519979D03*
X47368Y1527323D03*
X42644Y1521957D03*
X46845Y1514264D03*
X43000Y1526000D03*
X42960Y1517408D03*
X107000Y1576700D03*
X103500D03*
X110500D03*
X42919Y1583175D03*
X64525Y1591016D03*
X99500Y1713588D03*
Y1717988D03*
Y1694690D03*
Y1699090D03*
Y1675792D03*
Y1680192D03*
X105000Y1704739D03*
Y1707939D03*
Y1685841D03*
Y1689041D03*
X72500Y1683209D03*
X51635Y1665355D03*
X66400Y1706900D03*
X71000Y1747284D03*
X104000Y1747800D03*
X68000Y1750407D03*
Y1753607D03*
X99500Y1763981D03*
Y1768381D03*
X105000Y1774030D03*
Y1777230D03*
Y1723636D03*
Y1726836D03*
X67000Y1738000D03*
X71015D03*
X100300Y1820800D03*
X77159Y1818277D03*
X91036Y1835282D03*
X72123Y1841183D03*
X100287Y1825915D03*
X100300Y1830000D03*
X80600Y1848900D03*
X98000Y1848800D03*
X85000Y1817100D03*
X74100Y1796200D03*
X67800Y1855200D03*
X93625Y1802200D03*
X52000Y1877500D03*
X112366Y1883985D03*
X46868Y1887765D03*
X60897Y1885848D03*
X48000Y1877500D03*
X80400Y1957900D03*
X73400D03*
X76900D03*
X87500Y1954300D03*
X80400Y1954400D03*
X83900D03*
X73400D03*
X76900D03*
X57800Y1961800D03*
X177300Y39000D03*
X180800D03*
X184300D03*
X180800Y35500D03*
X177300D03*
X184300D03*
X152400Y41500D03*
X184461Y103368D03*
X125700Y54400D03*
X150557Y142854D03*
X167298Y147703D03*
X159500Y181000D03*
X124000Y128359D03*
Y131559D03*
X167298Y151203D03*
X114579Y137775D03*
X154875Y160500D03*
X173095Y244842D03*
X148000Y241500D03*
X180000Y235394D03*
X176800D03*
X144595Y223745D03*
Y228145D03*
X139095Y214896D03*
Y218096D03*
Y265290D03*
X172900Y249400D03*
X143600Y252100D03*
X129000Y255500D03*
X114295Y338300D03*
X144595Y274138D03*
Y278538D03*
Y293036D03*
Y297436D03*
Y311934D03*
Y316334D03*
X139095Y268490D03*
Y284187D03*
Y287387D03*
Y303085D03*
Y306285D03*
X171595Y308917D03*
X134000Y409500D03*
X137500D03*
X130500D03*
X127000D03*
X117000Y362500D03*
Y366000D03*
X113500Y362500D03*
Y366000D03*
X173800Y379800D03*
X157200Y412000D03*
X158500Y408000D03*
X127000Y413000D03*
X130500D03*
X134000D03*
X137500D03*
X170500Y478500D03*
X125300Y438000D03*
X157750Y541250D03*
X184500Y553500D03*
X124000Y533873D03*
Y537073D03*
X157750Y544750D03*
X159600Y581400D03*
X155500Y574000D03*
X144595Y629257D03*
X139095Y620408D03*
Y623608D03*
X150850Y574350D03*
X148000Y648000D03*
X173095Y650354D03*
X180000Y640906D03*
X176800D03*
X144595Y633657D03*
Y679650D03*
Y684050D03*
Y698548D03*
Y702948D03*
X139095Y670802D03*
Y674002D03*
Y689699D03*
Y692899D03*
X173000Y655200D03*
X117000Y771500D03*
Y768000D03*
X113500Y771500D03*
Y768000D03*
X117945Y743800D03*
X144595Y717446D03*
Y721846D03*
X139095Y708597D03*
Y711797D03*
X171595Y714429D03*
X127000Y818500D03*
X130500D03*
X134000D03*
X137500D03*
X134000Y815000D03*
X137500D03*
X130500D03*
X127000D03*
X156800Y816000D03*
X126800Y842500D03*
X143800Y807400D03*
X178000Y960000D03*
X162200Y988000D03*
X161095Y980622D03*
X167000Y939309D03*
Y942509D03*
X174500Y960000D03*
X157200Y950800D03*
X155900Y954200D03*
X157000Y957500D03*
X161200Y946100D03*
X161700Y950800D03*
X173095Y1055866D03*
X148000Y1053500D03*
X180000Y1046418D03*
X176800D03*
X144595Y1034769D03*
Y1039169D03*
X139095Y1025920D03*
Y1029120D03*
X137500Y1014500D03*
X173000Y1060400D03*
X139300Y1067000D03*
X144595Y1085162D03*
Y1089562D03*
Y1104060D03*
Y1108460D03*
Y1122958D03*
Y1127358D03*
X139095Y1076314D03*
Y1079514D03*
Y1095211D03*
Y1098411D03*
Y1114109D03*
Y1117309D03*
X171595Y1119941D03*
X117000Y1173500D03*
Y1177000D03*
X113500Y1173500D03*
Y1177000D03*
X117900Y1149200D03*
X127000Y1224000D03*
X130500Y1220500D03*
Y1224000D03*
X134000D03*
X137500D03*
X134000Y1220500D03*
X137500D03*
X127000D03*
X158052Y1216052D03*
X129150Y1252050D03*
X147956Y1347802D03*
X129500Y1344821D03*
Y1348021D03*
X154709Y1344513D03*
X140125Y1381300D03*
X167301Y1363238D03*
Y1366838D03*
X158875Y1376100D03*
X118000Y1470000D03*
X148000Y1458000D03*
X126000Y1466000D03*
X173095Y1461378D03*
X180000Y1451930D03*
X176800D03*
X144595Y1440281D03*
Y1444681D03*
Y1490674D03*
Y1495074D03*
X139095Y1431432D03*
Y1434632D03*
Y1481826D03*
Y1485026D03*
Y1500723D03*
X148095Y1468752D03*
X173100Y1466300D03*
X114000Y1573200D03*
X128250Y1506500D03*
X144595Y1509572D03*
Y1513972D03*
Y1528470D03*
Y1532870D03*
X139095Y1503923D03*
Y1519621D03*
Y1522821D03*
X171595Y1525453D03*
X126800Y1630100D03*
X130300D03*
X133800D03*
X126800Y1626600D03*
X130300D03*
X137300Y1630100D03*
Y1626600D03*
X133800D03*
X114000Y1576700D03*
X150200Y1628000D03*
X126900Y1654700D03*
X144400Y1720400D03*
X177717Y1778162D03*
X180075Y1790692D03*
X125000Y1750334D03*
Y1753534D03*
X136500Y1733000D03*
X137000Y1727500D03*
X140825Y1729825D03*
X157898Y1780145D03*
X140300Y1724100D03*
X147200Y1724400D03*
X173095Y1866890D03*
X148000Y1864000D03*
X180000Y1857442D03*
X176800D03*
X144595Y1850193D03*
Y1845793D03*
X139095Y1840144D03*
Y1836944D03*
X151452Y1810000D03*
X144595Y1900586D03*
Y1896186D03*
Y1919484D03*
Y1915084D03*
Y1938382D03*
Y1933982D03*
X139095Y1890538D03*
Y1887338D03*
Y1909435D03*
Y1906235D03*
Y1928333D03*
Y1925133D03*
X171595Y1930965D03*
X113500Y1875970D03*
X173500Y1871700D03*
X137300Y1969900D03*
X136800Y1959900D03*
X150800Y1958900D03*
X150600Y1970300D03*
X187800Y39000D03*
Y35500D03*
X208150Y32250D03*
X220500Y67500D03*
X198800Y158000D03*
Y162500D03*
Y167000D03*
X190500Y238501D03*
Y241701D03*
X188854Y527099D03*
Y530902D03*
X206500Y538750D03*
Y546250D03*
Y531250D03*
X195250Y561300D03*
Y576700D03*
X200250Y572100D03*
X190500Y644013D03*
Y647213D03*
X214700Y784200D03*
X190330Y913530D03*
X198900Y969500D03*
X207350Y968627D03*
X198900Y974000D03*
Y978500D03*
X229500Y946600D03*
X198900Y965477D03*
X208875Y957200D03*
X190500Y1049525D03*
Y1052725D03*
X196000Y1070300D03*
X193400Y1373000D03*
Y1377500D03*
Y1382000D03*
X214500Y1459000D03*
X190500Y1455037D03*
Y1458237D03*
X248500Y1713005D03*
Y1716808D03*
X197900Y1781500D03*
X251900Y1769900D03*
X203299Y1763350D03*
X197900Y1786000D03*
Y1790500D03*
X222500Y1776200D03*
X255495Y1738573D03*
X251692D03*
X203299Y1759750D03*
X224875Y1768100D03*
X190500Y1860549D03*
Y1863749D03*
X292600Y166955D03*
X318656Y391440D03*
X326156D03*
X293000Y385000D03*
X294500Y408000D03*
X315000Y412000D03*
X321400Y404400D03*
X327500Y377000D03*
X321500Y408500D03*
X312500Y393050D03*
X303200Y422600D03*
X313200Y427500D03*
X317000D03*
X321500Y425200D03*
Y417000D03*
Y421000D03*
X296470Y555500D03*
X292667D03*
X297300Y505017D03*
X273500Y597000D03*
Y589000D03*
Y585000D03*
Y577000D03*
X284000Y612000D03*
X273500Y573000D03*
Y565000D03*
X296000Y612000D03*
X292000D03*
X316000D03*
X308000D03*
X304000D03*
X290580Y559000D03*
X298450D03*
X320100Y587200D03*
X317500Y559000D03*
X286130Y615700D03*
X270000Y579030D03*
X310030Y615500D03*
X298030Y621000D03*
X269800Y590930D03*
X270000Y567130D03*
X289933Y615700D03*
X270000Y582833D03*
X313833Y615500D03*
X301833Y621000D03*
X269800Y594733D03*
X270000Y570933D03*
X293500Y738000D03*
X326167Y811099D03*
Y814902D03*
X292000Y837000D03*
X321500Y847000D03*
X315000Y842000D03*
X321500Y838500D03*
X321400Y834400D03*
X327500Y807000D03*
X312000Y824500D03*
X295200Y903000D03*
X305200D03*
Y913000D03*
X295200D03*
X303500Y853100D03*
X321500Y855200D03*
Y851000D03*
X317000Y857900D03*
X313200D03*
X292500Y965500D03*
X294000Y1111500D03*
X321400Y1205900D03*
X321500Y1210000D03*
X327500Y1178500D03*
X312500Y1194000D03*
X295000Y1245000D03*
X294500Y1254000D03*
X302500Y1224000D03*
X321600Y1226600D03*
X313200Y1228800D03*
X317000D03*
X314437Y1213382D03*
X321500Y1222500D03*
Y1218500D03*
X287167Y1380000D03*
X290970D03*
X319500Y1389000D03*
X301400Y1401500D03*
X315500Y1389000D03*
X293100Y1383500D03*
X284900D03*
X273500Y1419500D03*
Y1411500D03*
Y1423500D03*
X326500Y1417500D03*
Y1425700D03*
Y1405400D03*
Y1413500D03*
Y1429700D03*
X328000Y1381500D03*
Y1374000D03*
X327500Y1368500D03*
X273500Y1403500D03*
X307500Y1389000D03*
X330000Y1423470D03*
X270100Y1425697D03*
X330300Y1411100D03*
X270000Y1413530D03*
X330000Y1419667D03*
X270100Y1429500D03*
X330300Y1407297D03*
X270000Y1417333D03*
X273500Y1431500D03*
X287600Y1448000D03*
X279650D03*
X299600D03*
X291600D03*
X326500Y1437700D03*
X311600Y1448000D03*
X303600D03*
X330000Y1435170D03*
X293830Y1451500D03*
X305830Y1451300D03*
X282030Y1451400D03*
X330000Y1431367D03*
X297633Y1451500D03*
X309633Y1451300D03*
X285833Y1451400D03*
X318156Y1692440D03*
X325656D03*
X301800Y1722100D03*
X265500Y1722000D03*
X283500D03*
X285000Y1700600D03*
X295600Y1693400D03*
X285000Y1697400D03*
X292400Y1693400D03*
X315000Y1712000D03*
X321500Y1721000D03*
X327500Y1677000D03*
X321500Y1717000D03*
Y1708500D03*
X321400Y1704400D03*
X313500Y1692500D03*
X276402Y1726146D03*
X272599D03*
X297000Y1777000D03*
Y1752000D03*
X302000D03*
X321500Y1725200D03*
X317000Y1727300D03*
X313200D03*
X363750Y54250D03*
X382200Y81500D03*
X382000Y98000D03*
X358000Y64000D03*
X344500Y71750D03*
X360750Y124000D03*
X369000Y294000D03*
X401500Y410250D03*
X356257Y344176D03*
X391750Y344500D03*
X383750D03*
X348256Y344114D03*
X331500Y389000D03*
X365100Y371200D03*
X397000Y380250D03*
X375200Y371250D03*
X349870Y348870D03*
X331300Y408500D03*
X351729Y455810D03*
X379258Y455892D03*
X387249Y455882D03*
X343729Y455810D03*
X364758Y429249D03*
X375200Y429250D03*
X350137Y451250D03*
X385607Y451232D03*
X339500Y572667D03*
Y576470D03*
X332500Y605000D03*
X336000Y570580D03*
Y578600D03*
X332500Y593000D03*
Y601000D03*
X377250Y774500D03*
X385238Y774122D03*
X331500Y819000D03*
X358800Y803600D03*
X368700Y803750D03*
X388250Y803300D03*
X385196Y779112D03*
X331300Y838500D03*
X402000Y844000D03*
X360100Y808080D03*
X351792Y885835D03*
X379270Y885897D03*
X387292D03*
X343770D03*
X360800Y858500D03*
X375200Y858250D03*
X343894Y880707D03*
X379372Y880728D03*
X391758Y1145676D03*
X383757Y1145655D03*
X331500Y1190500D03*
X364300Y1174900D03*
X374200Y1174750D03*
X391900Y1150250D03*
X331300Y1210000D03*
X398750Y1188250D03*
X359175Y1179640D03*
X351750Y1257380D03*
X379270D03*
X387292Y1257360D03*
X343760Y1257381D03*
X365200Y1229800D03*
X400700Y1237500D03*
X375200Y1229750D03*
X343822Y1252222D03*
X379395Y1252274D03*
X356247Y1644123D03*
X348257Y1644132D03*
X356174Y1649291D03*
X331500Y1691000D03*
X369100Y1673700D03*
X385250Y1673000D03*
X331500Y1708500D03*
X395500Y1690500D03*
X376890Y1678000D03*
X376808Y1755434D03*
X373005D03*
X379000Y1736000D03*
X351750Y1755500D03*
X343750D03*
X383000Y1736300D03*
X365700Y1727700D03*
X383000Y1728700D03*
X375700Y1727750D03*
X343668Y1750741D03*
X379000Y1726000D03*
X405500Y277500D03*
X405000Y289000D03*
X410550Y420500D03*
X425890Y820729D03*
X425891Y812750D03*
X404000Y840500D03*
X420722Y820627D03*
X410550Y850500D03*
X405500Y1192000D03*
X408300Y1237500D03*
X425500Y1215250D03*
Y1223250D03*
X420763Y1223185D03*
X425879Y1721724D03*
X425500Y1713750D03*
X420732Y1721757D03*
X547659Y1560537D03*
X542159D03*
Y1566037D03*
X547659D03*
X663000Y535500D03*
X661500Y650500D03*
X662000Y826600D03*
X665000Y937000D03*
X660000Y1053500D03*
X662000Y1183500D03*
X657000Y1331500D03*
X662000Y1459000D03*
X634200Y1561200D03*
Y1565700D03*
X639700Y1561200D03*
Y1565700D03*
X646200Y1561200D03*
Y1565700D03*
X651700Y1561200D03*
Y1565700D03*
X753500Y1662000D03*
Y1666500D03*
X759000Y1662000D03*
Y1666500D03*
X765500Y1662000D03*
Y1666500D03*
X728700Y1933100D03*
X755995Y1968282D03*
X792343Y193599D03*
X832500Y171000D03*
X824500D03*
X816500D03*
X792343Y197402D03*
X836500Y362500D03*
X833000D03*
X840000Y366000D03*
Y362500D03*
X833000Y366000D03*
X836500D03*
X813350Y369250D03*
X782500Y648000D03*
X840000Y771500D03*
X833000D03*
X836500D03*
X840000Y768000D03*
X836500D03*
X833000D03*
X836500Y1177000D03*
X833000D03*
X840000D03*
Y1582500D03*
X833000D03*
X836500D03*
X840000Y1579000D03*
X836500D03*
X833000D03*
X813000Y1585750D03*
X808500Y1621500D03*
X814000D03*
Y1626000D03*
X808500D03*
X814000Y1630500D03*
X808500D03*
X771000Y1662000D03*
Y1666500D03*
X815000Y1785000D03*
X834750Y1823285D03*
X819000Y1839000D03*
X796339Y1937007D03*
Y1940507D03*
X804239Y1953307D03*
Y1956807D03*
X800739D03*
Y1953307D03*
X797239D03*
Y1956807D03*
X785239Y1960907D03*
X885531Y164804D03*
X896441Y147203D03*
X844000Y190000D03*
X866961Y162539D03*
X896547Y150803D03*
X890469Y164804D03*
X864975Y148875D03*
X876500Y251000D03*
X901441Y244842D03*
X908346Y235394D03*
X905146D03*
X872941Y223745D03*
Y228145D03*
X867441Y214896D03*
Y218096D03*
Y265290D03*
X901600Y249800D03*
X844050Y337300D03*
X872941Y274138D03*
Y278538D03*
Y293036D03*
Y297436D03*
Y311934D03*
Y316334D03*
X867441Y268490D03*
Y284187D03*
Y287387D03*
Y303085D03*
Y306285D03*
X899941Y308917D03*
X843500Y366000D03*
Y362500D03*
X895547Y552715D03*
X857735Y553465D03*
X895547Y556315D03*
X865125Y544000D03*
X883781Y564519D03*
X872941Y629257D03*
X867441Y620408D03*
Y623608D03*
X888719Y564519D03*
X876500Y648000D03*
X901441Y650354D03*
X908346Y640906D03*
X905146D03*
X872941Y633657D03*
Y679650D03*
Y684050D03*
Y698548D03*
Y702948D03*
X867441Y670802D03*
Y674002D03*
Y689699D03*
Y692899D03*
X901200Y655100D03*
X843500Y771500D03*
Y768000D03*
X846200Y743300D03*
X872941Y717446D03*
Y721846D03*
X867441Y708597D03*
Y711797D03*
X899941Y714429D03*
X883781Y970031D03*
X895547Y958227D03*
X857623Y958977D03*
X895547Y961827D03*
X888719Y970031D03*
X865125Y949600D03*
X901441Y1055866D03*
X876500Y1053500D03*
X908346Y1046418D03*
X905146D03*
X872941Y1034769D03*
Y1039169D03*
X867441Y1025920D03*
Y1029120D03*
X901300Y1060700D03*
X872941Y1085162D03*
Y1089562D03*
Y1104060D03*
Y1108460D03*
Y1122958D03*
Y1127358D03*
X867441Y1076314D03*
Y1079514D03*
Y1095211D03*
Y1098411D03*
Y1114109D03*
Y1117309D03*
X899941Y1119941D03*
X843500Y1177000D03*
X844600Y1148700D03*
X865125Y1346488D03*
X883219Y1373504D03*
X895647Y1363738D03*
X857688Y1364488D03*
X895647Y1367338D03*
X887438Y1373374D03*
X901441Y1461378D03*
X876500Y1459000D03*
X908346Y1451930D03*
X905146D03*
X872941Y1440281D03*
Y1444681D03*
Y1490674D03*
Y1495074D03*
X867441Y1431432D03*
Y1434632D03*
Y1481826D03*
Y1485026D03*
Y1500723D03*
X901400Y1466100D03*
X845600Y1554300D03*
X872941Y1509572D03*
Y1513972D03*
Y1528470D03*
Y1532870D03*
X867441Y1503923D03*
Y1519621D03*
Y1522821D03*
X899941Y1525453D03*
X843500Y1582500D03*
Y1579000D03*
X901500Y1681500D03*
X881353Y1650749D03*
X877853D03*
Y1654249D03*
X881353D03*
X896500Y1681000D03*
X859500Y1696000D03*
X898500Y1734000D03*
X910500Y1734600D03*
X895547Y1769250D03*
X883781Y1781054D03*
X895547Y1772850D03*
X888719Y1781054D03*
X865125Y1751800D03*
X902500Y1734000D03*
X910500Y1724700D03*
X876000Y1864000D03*
X901441Y1866890D03*
X908346Y1857442D03*
X905146D03*
X872941Y1845793D03*
Y1850193D03*
X867441Y1836944D03*
Y1840144D03*
X872941Y1896186D03*
Y1900586D03*
Y1915084D03*
Y1919484D03*
Y1933982D03*
Y1938382D03*
X867441Y1887338D03*
Y1890538D03*
Y1906235D03*
Y1909435D03*
Y1925133D03*
Y1928333D03*
X899941Y1930965D03*
X901200Y1871600D03*
X879500Y1970000D03*
X880000Y1955500D03*
X862000Y1969900D03*
Y1960500D03*
X844700Y1945200D03*
X926347Y155500D03*
Y160000D03*
Y164453D03*
X918846Y238501D03*
Y241701D03*
X926365Y561000D03*
Y569965D03*
Y565500D03*
X918846Y644013D03*
Y647213D03*
X926477Y966500D03*
Y971000D03*
Y975477D03*
X918846Y1049525D03*
Y1052725D03*
X926300Y1372000D03*
Y1380988D03*
Y1376500D03*
X918846Y1455037D03*
Y1458237D03*
X959000Y1631000D03*
X943500Y1646989D03*
X973000Y1641500D03*
X931000Y1659000D03*
X959000Y1657000D03*
Y1675000D03*
X926500Y1660000D03*
X941000Y1653000D03*
X934825Y1682285D03*
X947000Y1654500D03*
X915250Y1687500D03*
X919250Y1711500D03*
X926400Y1777500D03*
Y1782000D03*
Y1786500D03*
X921900Y1722400D03*
X918846Y1860549D03*
Y1863749D03*
G54D17*
X25000Y988000D03*
X27825Y995000D03*
X78675Y380704D03*
X47500Y660500D03*
X45000Y1057000D03*
X77607Y1565391D03*
X183344Y808200D03*
X126221Y861250D03*
Y853750D03*
X163170Y1210999D03*
X117387Y1536250D03*
Y1543750D03*
X122844Y1672400D03*
X130344D03*
X213244Y23725D03*
X243156Y382060D03*
X235656D03*
X228156Y438500D03*
X220656D03*
X206700Y575000D03*
X190844Y808200D03*
X242700Y1266656D03*
Y1259156D03*
X232344Y1740000D03*
X239844D03*
X284000Y541344D03*
Y548844D03*
X317156Y1193440D03*
X324656D03*
X276344Y1183060D03*
X268844D03*
X401500Y395500D03*
X393500Y422000D03*
X401500Y830000D03*
X393500Y852000D03*
X402000Y1196500D03*
X396637Y1176000D03*
X358156Y1411000D03*
X350656D03*
X402000Y1695000D03*
X379500Y1673750D03*
X427500Y297156D03*
Y304656D03*
X412500Y1130750D03*
Y1138250D03*
X438656Y1669000D03*
X431156D03*
X458156Y1743000D03*
X450656D03*
X512656Y623500D03*
X520156D03*
X555000Y524344D03*
Y531844D03*
X807756Y377775D03*
X808256Y783275D03*
X807756Y1188775D03*
Y1594275D03*
X979500Y1669750D03*
Y1662250D03*
G54D21*
X7600Y1855000D03*
X17500Y1827500D03*
X22600Y1825200D03*
X17500Y1832500D03*
X22500Y1830000D03*
X17500Y1837500D03*
X22500Y1835000D03*
X17500Y1842500D03*
X22500Y1840000D03*
X17500Y1847500D03*
X22500Y1845000D03*
X17500Y1852500D03*
X22500Y1850000D03*
X17500Y1857500D03*
X22500Y1855000D03*
Y1865000D03*
X17500Y1867500D03*
X22500Y1860000D03*
X12500Y1845000D03*
Y1850000D03*
Y1855000D03*
Y1840000D03*
X17500Y1872500D03*
X22500Y1870000D03*
X12500D03*
X71200Y36900D03*
X136100Y41200D03*
X935000Y1425000D03*
X984900Y1430400D03*
X953800Y1424900D03*
X945000Y1425000D03*
X935000Y1455000D03*
Y1475000D03*
Y1445000D03*
Y1465000D03*
Y1435000D03*
X945000Y1475000D03*
X955000D03*
X965000D03*
X945000Y1465000D03*
X955000D03*
X965000D03*
X945000Y1455000D03*
X955000D03*
X965000D03*
X945000Y1445000D03*
X955000D03*
X965000D03*
X945000Y1435000D03*
X955000D03*
X965000D03*
Y1495000D03*
X955000D03*
X935000Y1485000D03*
Y1495000D03*
X945000D03*
Y1485000D03*
X955000D03*
X965000D03*
X975000Y1495000D03*
Y1485000D03*
Y1475000D03*
Y1465000D03*
Y1455000D03*
Y1445000D03*
Y1435000D03*
X935000Y1505000D03*
X955000D03*
X945000D03*
X965000D03*
X990600Y1427100D03*
X995000Y1425000D03*
X1005000D03*
G54D19*
X36401Y1521623D03*
X32801D03*
X83248Y1059636D03*
X82748Y1465560D03*
X105700Y1548200D03*
X121600Y54700D03*
X148700Y413400D03*
X148600Y818700D03*
X157325Y1223850D03*
X123200Y1947250D03*
X205625Y38750D03*
X288000Y586484D03*
X313000Y559000D03*
X329600Y583200D03*
X332500Y597000D03*
Y589000D03*
X829388Y1695500D03*
X825388D03*
X833388D03*
X837388D03*
X825388Y1739500D03*
X829388D03*
X833388D03*
X837388D03*
X841388Y1695500D03*
X873962Y1672000D03*
Y1676500D03*
Y1681500D03*
Y1685500D03*
X906000Y1713500D03*
X891000Y1720000D03*
X916500Y1729500D03*
G54D11*
X20000Y40000D03*
Y20000D03*
X5500Y40982D03*
Y20982D03*
X10018Y5500D03*
X30018D03*
X20000Y80000D03*
Y100000D03*
Y120000D03*
Y60000D03*
X5500Y120982D03*
Y100982D03*
Y80982D03*
Y60982D03*
X20000Y160000D03*
Y180000D03*
Y140000D03*
X5500Y180982D03*
Y160982D03*
Y140982D03*
X20000Y240000D03*
Y200000D03*
Y220000D03*
X5500Y260982D03*
Y240982D03*
Y220982D03*
Y200982D03*
X23426Y281496D03*
X24764Y286496D03*
X28426Y290197D03*
X38465D03*
X42166Y286496D03*
X5500Y320982D03*
Y300982D03*
Y280982D03*
X20000Y380000D03*
Y400000D03*
X5500Y400982D03*
Y380982D03*
Y360982D03*
Y340982D03*
X20000Y340000D03*
Y460000D03*
Y440000D03*
Y480000D03*
Y420000D03*
X5500Y480982D03*
Y460982D03*
Y440982D03*
Y420982D03*
X20000Y540000D03*
Y500000D03*
Y520000D03*
X5500Y540982D03*
Y520982D03*
Y500982D03*
X24500Y624897D03*
Y612249D03*
Y599700D03*
X16500Y624765D03*
Y618765D03*
Y612166D03*
Y606166D03*
Y598197D03*
X24500Y700488D03*
Y687889D03*
Y675291D03*
Y662693D03*
Y637496D03*
X16500Y700355D03*
Y694355D03*
Y687757D03*
Y681757D03*
Y675158D03*
Y669158D03*
Y662226D03*
Y657000D03*
Y649500D03*
Y644530D03*
Y637363D03*
Y631363D03*
X24500Y769579D03*
Y756981D03*
Y725485D03*
Y712886D03*
X16500Y769646D03*
Y763646D03*
Y757048D03*
Y725552D03*
Y719552D03*
Y712953D03*
Y706953D03*
Y751658D03*
Y732500D03*
X24500Y841820D03*
Y829422D03*
Y816823D03*
Y804225D03*
Y791626D03*
X16500Y848686D03*
Y842087D03*
Y836087D03*
Y829489D03*
Y823489D03*
Y816891D03*
Y810891D03*
Y804292D03*
Y798292D03*
Y791694D03*
Y785694D03*
Y777725D03*
X24500Y905012D03*
Y892414D03*
Y879665D03*
Y867017D03*
Y854419D03*
X16500Y917678D03*
Y911678D03*
Y905079D03*
Y899079D03*
Y879883D03*
Y873883D03*
Y867284D03*
Y861284D03*
Y854686D03*
Y889500D03*
X36000Y960000D03*
X20000Y980000D03*
Y960000D03*
Y940000D03*
X16000Y931000D03*
X34500Y925000D03*
X5500Y980299D03*
X36500Y999500D03*
X5500Y1040299D03*
Y1020299D03*
Y1000299D03*
X24500Y1102601D03*
Y1115200D03*
X16500Y1140024D03*
Y1120828D03*
Y1114828D03*
Y1108229D03*
Y1102229D03*
Y1133500D03*
Y1094260D03*
X31707Y1086000D03*
X24500Y1203189D03*
Y1190590D03*
Y1177992D03*
Y1165394D03*
Y1152795D03*
Y1140197D03*
X16500Y1209016D03*
Y1203016D03*
Y1196418D03*
Y1190418D03*
Y1183820D03*
Y1177820D03*
Y1171221D03*
Y1165221D03*
Y1158623D03*
Y1152623D03*
Y1146024D03*
X24500Y1285079D03*
Y1272480D03*
Y1259882D03*
Y1228386D03*
Y1215787D03*
X16500Y1284906D03*
Y1278308D03*
Y1272308D03*
Y1265709D03*
Y1259709D03*
Y1253111D03*
Y1247721D03*
Y1221615D03*
Y1215615D03*
Y1228500D03*
X24500Y1357720D03*
Y1345121D03*
Y1332523D03*
Y1319924D03*
Y1297677D03*
X16500Y1357347D03*
Y1350749D03*
Y1344749D03*
Y1338150D03*
Y1332150D03*
Y1325552D03*
Y1319552D03*
Y1303505D03*
Y1297505D03*
Y1290906D03*
X16417Y1311583D03*
X24500Y1407913D03*
Y1395315D03*
Y1382716D03*
Y1370118D03*
X16500Y1413741D03*
Y1407741D03*
Y1401142D03*
Y1395142D03*
Y1388544D03*
Y1382544D03*
Y1375946D03*
Y1369946D03*
Y1363347D03*
X24500Y1560197D03*
Y1547598D03*
Y1522401D03*
Y1535000D03*
X16500Y1573000D03*
Y1566500D03*
Y1560500D03*
Y1554000D03*
Y1548000D03*
Y1541500D03*
Y1535000D03*
Y1529000D03*
Y1521031D03*
Y1512500D03*
X24500Y1632638D03*
Y1620039D03*
Y1607441D03*
Y1594842D03*
Y1582244D03*
X16500Y1644735D03*
Y1639845D03*
Y1633000D03*
Y1626500D03*
Y1620000D03*
Y1614000D03*
Y1607500D03*
Y1601500D03*
Y1595000D03*
Y1588500D03*
Y1582500D03*
X24500Y1717868D03*
Y1695821D03*
Y1683222D03*
Y1670624D03*
X16500Y1669933D03*
Y1677000D03*
Y1683170D03*
Y1689500D03*
Y1696000D03*
Y1702500D03*
Y1712000D03*
Y1717462D03*
Y1665044D03*
X24500Y1755663D03*
Y1743065D03*
Y1730466D03*
X22219Y1768323D03*
X16500Y1749000D03*
Y1756052D03*
Y1765000D03*
Y1774500D03*
Y1784000D03*
Y1790500D03*
Y1724000D03*
Y1730658D03*
Y1736500D03*
Y1743356D03*
X39500Y1823300D03*
X39400Y1819900D03*
X38400Y1846750D03*
X38300Y1859050D03*
X38800Y1810100D03*
X22100Y1802800D03*
X38317Y1804491D03*
X34900Y1807200D03*
X35100Y1813000D03*
X26500Y1805200D03*
X26600Y1810600D03*
X26300Y1815000D03*
X30800Y1805300D03*
Y1810500D03*
X17500Y1801900D03*
X22000Y1814100D03*
Y1809100D03*
X17500Y1806900D03*
Y1811900D03*
Y1816500D03*
X11615Y1922835D03*
X12953Y1927835D03*
X16615Y1931536D03*
X26654D03*
X30355Y1927835D03*
X31693Y1922835D03*
X5500Y1880685D03*
Y1888685D03*
X38500Y1871350D03*
X38200Y1883800D03*
X19974Y1943969D03*
X33700Y1960300D03*
X20000Y1960000D03*
Y1980000D03*
X32559Y1986626D03*
X12559D03*
X5500Y1973685D03*
Y1953685D03*
X40000Y40000D03*
Y20000D03*
X90018Y5500D03*
X110018D03*
X50018D03*
X70018D03*
X60000Y80000D03*
X40000D03*
Y100000D03*
Y120000D03*
Y60000D03*
X109038Y68476D03*
X109000Y87476D03*
X109160Y100476D03*
X96000Y114212D03*
Y107913D03*
Y98464D03*
Y89015D03*
Y79567D03*
Y70118D03*
Y60868D03*
X96100Y52300D03*
X72500Y91161D03*
Y86161D03*
X100000Y180000D03*
X99800Y194200D03*
X40000Y160000D03*
Y180000D03*
Y140000D03*
X67500Y135830D03*
X108917Y156976D03*
X72500Y166161D03*
X96000Y158307D03*
X72500Y151161D03*
X96000Y148858D03*
X72500Y136161D03*
X96000Y139409D03*
Y134000D03*
Y123661D03*
X104000Y125000D03*
X85250Y247238D03*
X80000Y200000D03*
X77306Y259381D03*
X40000Y240000D03*
Y200000D03*
Y220000D03*
X43504Y281496D03*
X109044Y473988D03*
X96000Y485079D03*
Y475630D03*
Y466181D03*
Y456732D03*
X67500Y541342D03*
X109000Y492988D03*
X109138Y511488D03*
X72500Y556673D03*
X96000Y554369D03*
X72500Y541673D03*
X96000Y544921D03*
Y539500D03*
Y529173D03*
Y519724D03*
Y513425D03*
Y503976D03*
Y494527D03*
X72500Y496673D03*
Y491673D03*
X104000Y531000D03*
X61100Y600100D03*
X80000Y600000D03*
X108917Y562488D03*
X72500Y571673D03*
X96000Y563819D03*
X85250Y652750D03*
X61500Y682500D03*
X102500Y737500D03*
X83200Y768300D03*
X76000Y706500D03*
X67500Y822500D03*
X51000Y913500D03*
X63500Y899000D03*
X65500Y867500D03*
X109040Y879500D03*
X109000Y898500D03*
X109187Y917000D03*
X96000Y918937D03*
Y909488D03*
Y900039D03*
Y890591D03*
Y881142D03*
Y871692D03*
Y862244D03*
X72500Y902185D03*
Y897185D03*
X67000Y953500D03*
X96532Y977682D03*
X107400Y994000D03*
X67500Y946855D03*
X109000Y968000D03*
X72500Y977185D03*
X96000Y969331D03*
X72500Y962185D03*
X96000Y959882D03*
X72500Y947185D03*
X96000Y950433D03*
Y945000D03*
Y934685D03*
Y925236D03*
X104000Y936000D03*
X99600Y1001400D03*
X102403Y1058209D03*
X103200Y1042500D03*
X71000Y1109000D03*
X111500Y1145000D03*
X109040Y1285012D03*
X96000Y1277205D03*
Y1267756D03*
X67500Y1352366D03*
X109000Y1304012D03*
X109133Y1322512D03*
X72500Y1352697D03*
X96000Y1355945D03*
Y1350500D03*
Y1340197D03*
Y1330748D03*
Y1324449D03*
Y1315000D03*
Y1305551D03*
Y1296103D03*
Y1286654D03*
X72500Y1307697D03*
Y1302697D03*
X104000Y1341000D03*
X109000Y1373512D03*
X70838Y1384165D03*
X96000Y1374843D03*
X72285Y1365633D03*
X96000Y1365393D03*
X80000Y1480000D03*
X109500Y1486000D03*
X90500Y1521500D03*
X96000Y1541100D03*
X72000Y1551500D03*
X72100Y1536400D03*
Y1509900D03*
X64500Y1581500D03*
X40500Y1608500D03*
X66500Y1694000D03*
X68000Y1651500D03*
X109040Y1690524D03*
X109000Y1709524D03*
X96000Y1701615D03*
Y1711063D03*
Y1673268D03*
X72500Y1708209D03*
X96000Y1682716D03*
Y1692166D03*
X72500Y1713209D03*
X96000Y1720512D03*
X100000Y1780000D03*
X67500Y1746128D03*
X109137Y1728024D03*
X109030Y1772524D03*
X96000Y1729961D03*
Y1736260D03*
Y1745109D03*
Y1755158D03*
Y1761457D03*
Y1770906D03*
X72500Y1758209D03*
Y1773209D03*
Y1788209D03*
X96000Y1780355D03*
X100000Y1759000D03*
X93600Y1848200D03*
X45100Y1850800D03*
X42300Y1846750D03*
X42200Y1859050D03*
X45200Y1839300D03*
Y1843300D03*
Y1854700D03*
X40800Y1832300D03*
Y1827300D03*
X76975Y1864000D03*
X100000Y1928000D03*
X80000D03*
X60000D03*
X74300Y1900000D03*
X107543Y1898024D03*
X111000Y1879570D03*
X100100Y1896300D03*
X80000Y1920000D03*
X60000D03*
Y1900000D03*
X44000D03*
X40556Y1917072D03*
X40000Y1940000D03*
X52000Y1887500D03*
X41700Y1883700D03*
X42100Y1871350D03*
X110700Y1974100D03*
X80000Y1980000D03*
X100300Y1980900D03*
X71666Y1961325D03*
X40000Y1980000D03*
X112559Y1986626D03*
X92559D03*
X72559D03*
X52559D03*
X94700Y1974100D03*
X98800D03*
X103300D03*
X107000D03*
X123819Y17717D03*
X125157Y22717D03*
X128819Y26418D03*
X138858D03*
X142559Y22717D03*
X143897Y17717D03*
X155018Y5500D03*
X170018D03*
X116600Y46800D03*
X180000Y80000D03*
X160000D03*
X140000D03*
X154700Y65000D03*
X150200D03*
X141700Y64900D03*
X138200D03*
X131700Y61300D03*
X128200D03*
X179147Y137913D03*
X180000Y180000D03*
X124000Y135859D03*
Y124059D03*
X147125Y160500D03*
X158300Y135200D03*
X176492Y231103D03*
X180100Y231095D03*
X140000Y247500D03*
X145800Y332400D03*
X131300D03*
X173000Y312500D03*
X131300Y335900D03*
X126445Y338300D03*
X124466Y370025D03*
X143500Y370000D03*
X147000D03*
X139500D03*
X136000D03*
X180000Y480000D03*
Y460000D03*
X120000D03*
X140000Y480000D03*
Y460000D03*
X160000Y440000D03*
X140000D03*
X120800Y438000D03*
X157500Y551200D03*
X160000Y520000D03*
X180000D03*
X124000Y541373D03*
Y529573D03*
X165138Y536500D03*
X174000Y553500D03*
X131500Y610500D03*
X180000Y620000D03*
Y580000D03*
X139500Y600400D03*
X180000Y600000D03*
X132350Y563750D03*
X176492Y636617D03*
X180308D03*
X140000Y654000D03*
X124966Y775525D03*
X125500Y719000D03*
X180000Y720000D03*
X136100Y775600D03*
X139600D03*
X147100D03*
X143600D03*
X145800Y737100D03*
X131400Y738200D03*
X173000Y718000D03*
X131400Y741700D03*
X122445Y743800D03*
X116000Y814500D03*
X122251Y842400D03*
X160000Y880000D03*
X140000Y900000D03*
X180000Y980000D03*
X167000Y945909D03*
Y935909D03*
X180000Y1000000D03*
X176492Y1042129D03*
X180308D03*
X140000Y1059500D03*
X129000Y1051500D03*
X180000Y1140000D03*
X129500Y1084500D03*
X122500Y1107000D03*
X123500Y1123500D03*
X180000Y1120000D03*
Y1100000D03*
Y1080000D03*
X147800Y1140000D03*
X173000Y1123500D03*
X124100Y1181025D03*
X143500Y1180400D03*
X147000D03*
X139500D03*
X136000D03*
X131500Y1143200D03*
Y1146700D03*
X122400Y1149200D03*
X120000Y1280000D03*
X140000D03*
X160000D03*
X180000D03*
X120000Y1220000D03*
X180000D03*
X118250Y1252050D03*
X179147Y1353048D03*
X160000Y1340000D03*
X180000D03*
X140000D03*
Y1300000D03*
X160000D03*
X180000D03*
X129500Y1352321D03*
Y1340521D03*
X121320Y1425396D03*
X117690Y1397168D03*
X143087Y1403623D03*
X180000Y1400000D03*
Y1420000D03*
X160000Y1360000D03*
X151125Y1376608D03*
X126916Y1447364D03*
X180000Y1440000D03*
Y1500000D03*
X176492Y1447634D03*
X180308D03*
X130000Y1470000D03*
X122000D03*
X114000D03*
X140000Y1464000D03*
X147700Y1545500D03*
X123400Y1522600D03*
X116500Y1505500D03*
X180000Y1520000D03*
X130600Y1549100D03*
X173000Y1529000D03*
X123500Y1505200D03*
X144200Y1545500D03*
X113841Y1580900D03*
X181500Y1641500D03*
X182500Y1622500D03*
X172000Y1595000D03*
X171500Y1613500D03*
X143300Y1586900D03*
X146800D03*
X138800Y1585100D03*
X135300D03*
X160200Y1710300D03*
X117300Y1696500D03*
X136600Y1681900D03*
X121700Y1654800D03*
X143000Y1656000D03*
X137000Y1666500D03*
X120000Y1678000D03*
X123000Y1702000D03*
X136700Y1720100D03*
X160000Y1720000D03*
Y1700000D03*
X180000D03*
Y1680000D03*
X117000Y1654600D03*
X159800Y1730000D03*
X148000Y1787000D03*
X125000Y1757834D03*
Y1746034D03*
X128800Y1854000D03*
X145500Y1807500D03*
X136500Y1811500D03*
X140000Y1820000D03*
X160000Y1800000D03*
X180000D03*
Y1840000D03*
X180308Y1853146D03*
X176492D03*
X128800Y1921300D03*
X129500Y1883500D03*
X115228Y1879770D03*
X128200Y1900300D03*
X180000Y1880000D03*
Y1900000D03*
Y1940000D03*
X173000Y1934500D03*
X140000Y1870000D03*
X133000Y1977100D03*
X114200Y1974100D03*
X118500Y1971400D03*
X139100Y1977100D03*
X172559Y1986626D03*
X152559D03*
X132559D03*
X130500Y1946200D03*
X240000Y20000D03*
Y40000D03*
X230018Y5500D03*
X250018D03*
X190018D03*
X210018D03*
X220000Y80000D03*
X240000D03*
X200000D03*
X240000Y140000D03*
X220000D03*
Y160000D03*
X240000D03*
X200000Y180000D03*
X220000D03*
X240000D03*
X200000Y200000D03*
X240000Y220000D03*
X220000D03*
Y200000D03*
X240000D03*
X200000Y260000D03*
X240000D03*
X220000D03*
X194500Y243300D03*
X200000Y280000D03*
X220000D03*
X240000D03*
Y320000D03*
Y300000D03*
X220000D03*
X200000D03*
Y320000D03*
X220000D03*
X240000Y340000D03*
X220000Y360000D03*
X240000D03*
X220000Y340000D03*
X200000D03*
Y360000D03*
X220000Y480000D03*
X200000D03*
X220000Y460000D03*
X200000D03*
X220000Y420000D03*
X200000Y440000D03*
Y420000D03*
Y520000D03*
X220000D03*
X195500Y531250D03*
Y546250D03*
Y538750D03*
X220000Y620000D03*
X240000Y600000D03*
Y580000D03*
X200000D03*
Y700000D03*
X220000D03*
Y680000D03*
X200000D03*
Y660000D03*
X220000D03*
Y640000D03*
X190500Y651513D03*
X240000Y760000D03*
X220000Y720000D03*
Y740000D03*
X200000Y760000D03*
Y740000D03*
Y720000D03*
Y900000D03*
X240000Y860000D03*
X220000D03*
Y880000D03*
X240000D03*
X194200Y985900D03*
X220000Y940000D03*
X240000D03*
X201125Y957200D03*
X195500Y949750D03*
X220000Y1040000D03*
Y1020000D03*
X240000D03*
Y1000000D03*
Y1060000D03*
X220000D03*
X240000Y1040000D03*
X190600Y1057024D03*
X200000Y1080000D03*
Y1100000D03*
Y1140000D03*
Y1120000D03*
X220000Y1140000D03*
Y1120000D03*
X240000D03*
Y1100000D03*
X220000D03*
Y1080000D03*
X240000D03*
X255674Y1099470D03*
X208500Y1190000D03*
X200000Y1200000D03*
X240000D03*
Y1180000D03*
X200000Y1160000D03*
Y1280000D03*
X220000D03*
X240000D03*
Y1220000D03*
X220000D03*
X200000Y1340000D03*
X220000D03*
X240000D03*
X200000Y1300000D03*
X220000D03*
X240000D03*
X227000Y1359500D03*
X215000Y1368000D03*
X240000Y1367500D03*
Y1420000D03*
Y1400000D03*
Y1460000D03*
Y1440000D03*
X200000D03*
Y1460000D03*
Y1480000D03*
X240000D03*
Y1500000D03*
X200000D03*
X190400Y1450738D03*
X202000Y1534000D03*
X200000Y1520000D03*
X220000D03*
X240000D03*
X200000Y1560000D03*
X220000D03*
X240000D03*
X203500Y1618500D03*
X229500Y1614500D03*
X189300Y1577200D03*
X220000Y1580000D03*
X242500Y1702500D03*
X251800Y1718400D03*
X220000Y1720000D03*
X200000Y1660000D03*
Y1680000D03*
X220000D03*
Y1660000D03*
X240000Y1680000D03*
Y1660000D03*
X220200Y1740900D03*
X206000Y1735000D03*
X256000Y1745500D03*
X220000Y1734500D03*
X207600Y1777500D03*
X220800Y1763750D03*
X191353Y1772940D03*
X200000Y1800000D03*
X220000D03*
X240000D03*
X220000Y1840000D03*
X240000D03*
X194620Y1865000D03*
X200000Y1880000D03*
Y1900000D03*
X220000D03*
X240000Y1920000D03*
X220000D03*
X200000D03*
Y1940000D03*
X220000D03*
X240000D03*
X256549Y1898366D03*
X240000Y1880000D03*
X256500D03*
X200000Y1980000D03*
Y1960000D03*
X220000Y1980000D03*
Y1960000D03*
X240000Y1980000D03*
Y1960000D03*
X252559Y1986626D03*
X232559D03*
X212559D03*
X192559D03*
X300000Y40000D03*
Y20000D03*
X320000D03*
Y40000D03*
X260000D03*
Y20000D03*
X280000D03*
Y40000D03*
X310018Y5500D03*
X330018D03*
X270018D03*
X290018D03*
X320000Y80000D03*
X300000Y60000D03*
X320000D03*
Y120000D03*
X300000D03*
X280000D03*
X260000Y100000D03*
X280000D03*
X300000D03*
X320000D03*
X300000Y80000D03*
X280000D03*
X260000D03*
Y160000D03*
X320000D03*
X300000Y140000D03*
X320000D03*
X260000Y180000D03*
X280000D03*
Y220000D03*
X260000D03*
Y200000D03*
X280000D03*
X300000D03*
Y220000D03*
X320000D03*
Y240000D03*
X265552Y279528D03*
X266890Y284528D03*
X270552Y288229D03*
X280591D03*
X284292Y284528D03*
X285630Y279528D03*
X320000Y320000D03*
X300000D03*
X280000D03*
X260000D03*
X320000Y280000D03*
X300000D03*
X260000Y300000D03*
X280000Y360000D03*
X260000D03*
Y340000D03*
X280000D03*
X300000D03*
X320000D03*
X304553Y374081D03*
X313500Y386000D03*
X309000Y365000D03*
X313500Y362000D03*
X320000Y359500D03*
X327500Y373000D03*
X305100Y407700D03*
X304400Y416200D03*
X280000Y460000D03*
Y480000D03*
X300000D03*
Y460000D03*
X320000D03*
X300000Y440000D03*
X280000D03*
Y420000D03*
X260000D03*
Y440000D03*
Y480000D03*
Y460000D03*
X321500Y413000D03*
X260000Y520000D03*
X320000Y540000D03*
X260000Y560000D03*
Y600000D03*
X280000Y620000D03*
X260000D03*
X302500Y583000D03*
X297500D03*
Y588000D03*
X302500D03*
X300000Y585500D03*
X265552Y685030D03*
X266890Y690030D03*
X270552Y693731D03*
X280591D03*
X284292Y690030D03*
X285630Y685030D03*
X298500Y660200D03*
Y680200D03*
X320000Y700000D03*
X260000D03*
X320000Y640000D03*
X300000D03*
X280000D03*
X260000D03*
X298200Y720000D03*
X260000D03*
X320000D03*
X304400Y846700D03*
X321500Y807000D03*
X297840Y804552D03*
X280000Y820000D03*
X325053Y782652D03*
X309000Y795000D03*
X321500Y843000D03*
X323000Y819500D03*
X313500Y792000D03*
X320000Y789500D03*
X327500Y803000D03*
X304500Y836700D03*
X301300Y822550D03*
X260000Y860000D03*
Y880000D03*
X300000D03*
X280000D03*
Y860000D03*
X260000Y940000D03*
X280000D03*
X300000D03*
X260000Y980000D03*
X280000D03*
X300000D03*
X320000Y1060000D03*
X300000D03*
X260000D03*
Y1040000D03*
X280000D03*
X300000D03*
X320000D03*
Y1020000D03*
X280000D03*
X300000D03*
X260000D03*
X280000Y1000000D03*
X300000D03*
X320000D03*
X265552Y1088573D03*
X266890Y1093573D03*
X270552Y1097274D03*
X280591D03*
X284292Y1093573D03*
X285630Y1088573D03*
X320000Y1140000D03*
X260000Y1120000D03*
X280000D03*
X300000D03*
X320000Y1100000D03*
X300000D03*
Y1080000D03*
X320000D03*
X260000Y1200000D03*
X280000D03*
Y1180000D03*
X260000Y1160000D03*
X296011Y1185470D03*
X309000Y1166500D03*
X295400Y1172655D03*
X313500Y1187500D03*
X320000Y1161000D03*
X327500Y1174500D03*
X305200Y1208300D03*
X304500Y1217500D03*
X320000Y1280000D03*
X300000Y1240000D03*
X320000Y1260000D03*
X300000Y1280000D03*
Y1260000D03*
X280000Y1280000D03*
X260000D03*
Y1260000D03*
X280000D03*
Y1220000D03*
X260000D03*
X321500Y1214500D03*
X280000Y1340000D03*
X260000D03*
X300000Y1300000D03*
X280000D03*
X260000D03*
X311500Y1389000D03*
X280000Y1380000D03*
X260000Y1400000D03*
Y1420000D03*
X300000Y1421500D03*
X302500Y1424000D03*
X297500D03*
Y1419000D03*
X302500D03*
X303500Y1389000D03*
X297600Y1392000D03*
X273500Y1407500D03*
X260000Y1440000D03*
X300984Y1433500D03*
X260000Y1520000D03*
X280000D03*
X300000D03*
X320000Y1540000D03*
Y1560000D03*
X300000D03*
X280000D03*
X260000D03*
X258585Y1508386D03*
X260000Y1620000D03*
Y1600000D03*
X300000Y1620000D03*
X280000Y1600000D03*
Y1620000D03*
X300000Y1600000D03*
X320000D03*
X289300Y1696200D03*
Y1701800D03*
X306200Y1689400D03*
X259000Y1702500D03*
X260000Y1680000D03*
Y1660000D03*
X321500Y1713000D03*
X327500Y1673000D03*
X305300Y1715700D03*
X306200Y1709600D03*
X320000Y1760000D03*
Y1780000D03*
X260000Y1740000D03*
X288000Y1742500D03*
X293000D03*
X284000Y1731250D03*
X268800Y1774600D03*
X260000Y1800000D03*
Y1840000D03*
X280000D03*
X320000Y1860000D03*
X300000D03*
Y1840000D03*
X320000Y1820000D03*
Y1840000D03*
X271500Y1795000D03*
X279500D03*
X287500D03*
X300000Y1800000D03*
X265552Y1903534D03*
X266890Y1908534D03*
X270552Y1912235D03*
X280591D03*
X284292Y1908534D03*
X285630Y1903534D03*
X320000Y1940000D03*
X300000D03*
X280000D03*
X260000D03*
X280071Y1924667D03*
X300000Y1900000D03*
Y1920000D03*
X320000D03*
Y1900000D03*
X300000Y1880000D03*
X320000D03*
X260000Y1980000D03*
Y1960000D03*
X280000Y1980000D03*
Y1960000D03*
X300000Y1980000D03*
Y1960000D03*
X320000Y1980000D03*
Y1960000D03*
X312559Y1986626D03*
X292559D03*
X272559D03*
X380000Y20000D03*
Y40000D03*
X400000D03*
Y20000D03*
X340000Y40000D03*
Y20000D03*
X360000Y40000D03*
Y20000D03*
X390018Y5500D03*
X350018D03*
X370018D03*
X400000Y100000D03*
Y80000D03*
X377500Y98000D03*
X400000Y60000D03*
X340000Y80000D03*
Y100000D03*
Y60000D03*
X400000Y120000D03*
X340000D03*
X373500Y98000D03*
X363750Y65250D03*
X352500Y68500D03*
X358500Y93500D03*
X363750Y73300D03*
X340000Y180000D03*
X360000D03*
X380000D03*
X400000D03*
Y140000D03*
Y160000D03*
X380000Y140000D03*
Y160000D03*
X360000Y140000D03*
Y160000D03*
X340000D03*
Y140000D03*
X357250Y124000D03*
X400000Y220000D03*
Y200000D03*
X380000D03*
X340000Y240000D03*
Y260000D03*
X360000D03*
Y280000D03*
X370000Y411000D03*
Y405500D03*
X375500D03*
X381000D03*
X375500Y411000D03*
X381000D03*
X359000D03*
X364500D03*
Y405500D03*
X359000D03*
X370000Y400000D03*
X381000D03*
X375500D03*
X370000Y389000D03*
Y394500D03*
X375500D03*
Y389000D03*
X381000D03*
Y394500D03*
X364500Y400000D03*
X365000Y394500D03*
Y389000D03*
X359000D03*
Y394500D03*
Y400000D03*
X337500Y406250D03*
X331500Y393000D03*
X401500Y401500D03*
X397000Y383750D03*
X400000Y440000D03*
Y460000D03*
Y480000D03*
X339500Y416750D03*
X370397Y439122D03*
X368500Y436000D03*
X372000D03*
X397000Y414750D03*
X379250Y451000D03*
X385896Y444265D03*
X343750Y451000D03*
X350241Y444377D03*
X400000Y540000D03*
X340000D03*
X380000Y500000D03*
Y540000D03*
X400000Y520000D03*
Y560000D03*
X360000Y580000D03*
X340000Y560000D03*
Y600000D03*
Y620000D03*
X380000D03*
X400000D03*
X380000Y560000D03*
Y660000D03*
X400000Y640000D03*
Y680000D03*
Y700000D03*
X340000Y660000D03*
Y680000D03*
Y700000D03*
X360000D03*
Y680000D03*
Y660000D03*
Y640000D03*
X380000D03*
X400000Y740000D03*
Y720000D03*
X340000Y740000D03*
Y720000D03*
X360000D03*
X400000Y780000D03*
X340000D03*
X370000Y841000D03*
Y835500D03*
X375500D03*
X381000D03*
X375500Y841000D03*
X381000D03*
X359000D03*
X364500D03*
Y835500D03*
X359000D03*
X370000Y830000D03*
X381000D03*
X375500D03*
X370000Y819000D03*
Y824500D03*
X375500D03*
Y819000D03*
X381000D03*
Y824500D03*
X364500Y830000D03*
X365000Y824500D03*
Y819000D03*
X359000D03*
Y824500D03*
Y830000D03*
X397000Y844750D03*
X339500Y846750D03*
X337500Y836250D03*
X331500Y823000D03*
X401500Y836000D03*
X395000Y806500D03*
X371059Y903347D03*
X355622Y919857D03*
X380000Y920000D03*
X400000D03*
Y900000D03*
X368500Y865000D03*
X372000D03*
X379228Y874277D03*
X387250Y881000D03*
X351740Y880717D03*
X343749Y874298D03*
X335823Y940330D03*
X340000Y980000D03*
X360000D03*
X380000D03*
X400000D03*
Y960000D03*
X380000D03*
X340000D03*
X360000D03*
Y940000D03*
X380000D03*
X400000D03*
Y1060000D03*
X380000D03*
X400000Y1040000D03*
X380000D03*
X360000Y1060000D03*
X340000D03*
X360000Y1040000D03*
X340000D03*
Y1000000D03*
Y1020000D03*
X360000Y1000000D03*
Y1020000D03*
X380000Y1000000D03*
Y1020000D03*
X400000Y1000000D03*
Y1020000D03*
X360000Y1140000D03*
X340000D03*
X380000Y1100000D03*
X400000Y1080000D03*
X380000D03*
X360000Y1100000D03*
X340000D03*
X360000Y1080000D03*
X340000D03*
Y1160000D03*
X354228Y1164233D03*
X370000Y1212500D03*
Y1207000D03*
X375500D03*
X381000D03*
X375500Y1212500D03*
X381000D03*
X359000D03*
X364500D03*
Y1207000D03*
X359000D03*
X370000Y1201500D03*
X381000D03*
X375500D03*
X370000Y1190500D03*
Y1196000D03*
X375500D03*
Y1190500D03*
X381000D03*
Y1196000D03*
X364500Y1201500D03*
X365000Y1196000D03*
Y1190500D03*
X359000D03*
Y1196000D03*
Y1201500D03*
X337500Y1207750D03*
X331500Y1194500D03*
X402000Y1202500D03*
X396750Y1181250D03*
X400000Y1280000D03*
Y1260000D03*
X339500Y1218250D03*
X370200Y1239700D03*
X368500Y1236500D03*
X372000D03*
X343749Y1245719D03*
X351771Y1252213D03*
X379249Y1245782D03*
X387208Y1252212D03*
X391500Y1218500D03*
X400000Y1340000D03*
X380000D03*
Y1320000D03*
X400000D03*
X380000Y1300000D03*
X400000D03*
X360000Y1340000D03*
Y1320000D03*
X340000Y1340000D03*
X380000Y1420000D03*
Y1400000D03*
X400000Y1420000D03*
Y1400000D03*
Y1380000D03*
Y1360000D03*
X380000D03*
Y1380000D03*
X360000D03*
Y1360000D03*
X340000D03*
Y1380000D03*
X380000Y1500000D03*
X360000D03*
X340000Y1480000D03*
Y1460000D03*
X400000D03*
X380000Y1440000D03*
X400000D03*
X360000Y1560000D03*
X400000Y1540000D03*
X380000D03*
X360000D03*
Y1520000D03*
X380000D03*
X400000D03*
Y1580000D03*
X380000D03*
X334500Y1650000D03*
Y1665000D03*
X380000Y1660000D03*
X400000D03*
X359000Y1705500D03*
Y1700000D03*
Y1694500D03*
Y1689000D03*
X365000D03*
Y1694500D03*
X364500Y1700000D03*
Y1705500D03*
Y1711000D03*
X359000D03*
X381000D03*
X375500D03*
X381000Y1705500D03*
X375500D03*
X381000Y1694500D03*
Y1689000D03*
X375500D03*
Y1694500D03*
X370000D03*
Y1689000D03*
Y1705500D03*
Y1711000D03*
X381000Y1700000D03*
X375500D03*
X370000D03*
X402000Y1701000D03*
X339500Y1716750D03*
X337500Y1706250D03*
X331500Y1695000D03*
X388750Y1673000D03*
X368500Y1768000D03*
X400000Y1760000D03*
X365400Y1734400D03*
X369000Y1734500D03*
X372500D03*
X393000Y1723500D03*
X351750Y1751000D03*
X343709Y1744187D03*
X400000Y1860000D03*
X380000D03*
X360000D03*
X340000D03*
Y1800000D03*
Y1840000D03*
X360000D03*
X380000D03*
X400000D03*
Y1820000D03*
X380000D03*
X360000D03*
X340000D03*
X360000Y1800000D03*
X400000D03*
X380000D03*
X400000Y1940000D03*
X380000D03*
X360000D03*
X340000D03*
Y1900000D03*
Y1920000D03*
X360000D03*
Y1900000D03*
X380000D03*
Y1920000D03*
X400000D03*
Y1900000D03*
X340000Y1880000D03*
X360000D03*
X380000D03*
X400000D03*
X340000Y1980000D03*
Y1960000D03*
X360000Y1980000D03*
Y1960000D03*
X380000Y1980000D03*
Y1960000D03*
X400000Y1980000D03*
Y1960000D03*
X392559Y1986626D03*
X372559D03*
X352559D03*
X332559D03*
X460000Y20000D03*
Y40000D03*
X420000Y20000D03*
Y40000D03*
X440000D03*
Y20000D03*
X470018Y5500D03*
X410018D03*
X430018D03*
X450018D03*
X460000Y100000D03*
X420000D03*
X440000D03*
X460000Y80000D03*
Y60000D03*
X440000D03*
Y80000D03*
X420000D03*
Y60000D03*
X460000Y120000D03*
X440000D03*
X420000D03*
Y180000D03*
X440000D03*
X460000D03*
Y140000D03*
Y160000D03*
X440000D03*
Y140000D03*
X420000D03*
Y160000D03*
Y200000D03*
X460000D03*
X440000D03*
X420000Y220000D03*
X440000D03*
X460000D03*
Y240000D03*
X440000D03*
X420000D03*
Y260000D03*
X440000D03*
X460000D03*
X440000Y280000D03*
X460000D03*
X440000Y320000D03*
X460000D03*
Y300000D03*
X440000Y400000D03*
X460000D03*
Y380000D03*
X440000D03*
Y360000D03*
X460000D03*
Y340000D03*
X440000D03*
X460000Y480000D03*
Y460000D03*
X440000Y480000D03*
Y460000D03*
Y440000D03*
X460000D03*
Y420000D03*
X440000D03*
X420000Y520000D03*
Y540000D03*
X440000D03*
Y520000D03*
X460000D03*
Y500000D03*
X420000D03*
Y620000D03*
X440000Y600000D03*
X460000Y580000D03*
X420000Y600000D03*
X440000Y580000D03*
X420000Y560000D03*
Y700000D03*
X460000Y660000D03*
Y680000D03*
Y700000D03*
X420000Y680000D03*
Y660000D03*
Y720000D03*
Y740000D03*
X460000Y720000D03*
Y760000D03*
X420000D03*
Y840000D03*
X440000D03*
X460000D03*
Y820000D03*
Y800000D03*
Y780000D03*
X420000D03*
Y920000D03*
X440000D03*
X460000D03*
Y900000D03*
X440000D03*
X420000D03*
Y880000D03*
X460000D03*
X440000D03*
X420000Y860000D03*
X440000D03*
X460000D03*
X420000Y980000D03*
X440000D03*
X460000D03*
Y960000D03*
X440000D03*
X420000D03*
Y940000D03*
X440000D03*
X460000D03*
X420000Y1060000D03*
X440000Y1040000D03*
X420000D03*
Y1000000D03*
Y1020000D03*
X440000Y1000000D03*
Y1020000D03*
X460000D03*
Y1000000D03*
X440000Y1120000D03*
X460000D03*
Y1080000D03*
X420000Y1200000D03*
X440000D03*
X460000D03*
Y1160000D03*
Y1180000D03*
X440000Y1160000D03*
Y1180000D03*
X420000Y1160000D03*
Y1180000D03*
Y1280000D03*
Y1240000D03*
X440000D03*
X460000D03*
Y1260000D03*
X440000D03*
X420000D03*
X460000Y1280000D03*
X440000D03*
X420000Y1340000D03*
Y1320000D03*
X440000D03*
Y1340000D03*
X460000D03*
Y1320000D03*
X440000Y1300000D03*
X420000D03*
X460000D03*
X440000Y1420000D03*
X420000D03*
Y1400000D03*
Y1380000D03*
Y1360000D03*
X440000Y1400000D03*
Y1360000D03*
Y1380000D03*
X460000D03*
Y1360000D03*
Y1420000D03*
Y1400000D03*
X440000Y1500000D03*
X420000Y1480000D03*
X440000D03*
Y1460000D03*
X420000D03*
Y1440000D03*
X440000D03*
X460000Y1500000D03*
Y1480000D03*
Y1460000D03*
Y1440000D03*
X420000Y1540000D03*
X460000Y1520000D03*
Y1580000D03*
X440000D03*
X420000D03*
Y1700000D03*
Y1680000D03*
Y1660000D03*
X440000Y1680000D03*
X460000D03*
Y1660000D03*
X420000Y1760000D03*
X406500Y1736500D03*
X440000Y1780000D03*
Y1760000D03*
X460000D03*
Y1780000D03*
X450000Y1803500D03*
X440000Y1860000D03*
X420000D03*
Y1840000D03*
X440000D03*
X420000Y1820000D03*
X460000Y1840000D03*
Y1860000D03*
Y1940000D03*
X440000D03*
X420000D03*
Y1900000D03*
Y1920000D03*
X440000D03*
Y1900000D03*
X460000Y1920000D03*
Y1900000D03*
X420000Y1880000D03*
X440000D03*
X460000D03*
X420000Y1980000D03*
Y1960000D03*
X440000Y1980000D03*
Y1960000D03*
X460000Y1980000D03*
Y1960000D03*
X472559Y1986626D03*
X452559D03*
X432559D03*
X412559D03*
X500000Y40000D03*
X480000D03*
X520000D03*
X530018Y5500D03*
X510018D03*
X490018D03*
X500000Y20000D03*
X480000D03*
X520000D03*
X540000Y40000D03*
Y20000D03*
Y100000D03*
X520000D03*
X500000D03*
X480000D03*
Y120000D03*
X500000D03*
X520000D03*
X480000Y60000D03*
Y80000D03*
X500000D03*
Y60000D03*
X520000D03*
Y80000D03*
X540000Y120000D03*
Y80000D03*
Y60000D03*
X480000Y140000D03*
Y160000D03*
X500000D03*
Y140000D03*
X520000D03*
Y160000D03*
Y180000D03*
X500000D03*
X480000D03*
X540000Y160000D03*
Y140000D03*
Y180000D03*
X520000Y260000D03*
X500000D03*
X520000Y240000D03*
X480000D03*
X500000D03*
Y220000D03*
X480000D03*
Y200000D03*
X500000D03*
X520000D03*
Y220000D03*
X540000Y260000D03*
Y220000D03*
Y240000D03*
Y200000D03*
X500000Y280000D03*
X520000D03*
X480000D03*
Y300000D03*
X500000D03*
X520000D03*
Y320000D03*
X500000D03*
X480000D03*
X540000Y280000D03*
Y300000D03*
Y320000D03*
X500000Y400000D03*
X520000D03*
Y380000D03*
X540000Y400000D03*
Y380000D03*
Y360000D03*
Y340000D03*
X480000Y400000D03*
Y340000D03*
X500000D03*
X520000D03*
Y360000D03*
X500000D03*
X480000D03*
Y380000D03*
Y440000D03*
X500000D03*
X480000Y420000D03*
X500000D03*
X520000D03*
X540000D03*
X520000Y480000D03*
X500000D03*
X480000D03*
Y460000D03*
X500000D03*
X520000D03*
Y440000D03*
X540000Y460000D03*
Y440000D03*
X500000Y500000D03*
X480000D03*
X520000Y520000D03*
X500000Y540000D03*
X540000D03*
X520000Y560000D03*
X540000D03*
Y580000D03*
X500000D03*
Y600000D03*
X520000D03*
X540000D03*
X520000Y580000D03*
X480000Y560000D03*
X540000Y700000D03*
X520000D03*
X500000D03*
X480000D03*
X540000Y680000D03*
X520000D03*
X500000D03*
X480000D03*
X540000Y660000D03*
X520000D03*
X500000D03*
X480000D03*
Y640000D03*
X500000D03*
X520000D03*
X540000D03*
X520000Y720000D03*
X500000D03*
X480000D03*
X540000Y740000D03*
X480000Y760000D03*
X500000D03*
X520000D03*
X540000D03*
X520000Y780000D03*
X500000D03*
X480000D03*
Y800000D03*
X500000D03*
X520000D03*
X480000Y820000D03*
X500000D03*
X520000D03*
X480000Y840000D03*
X500000D03*
X520000D03*
X540000D03*
Y780000D03*
Y800000D03*
Y820000D03*
X520000Y900000D03*
Y920000D03*
X500000D03*
X480000D03*
X520000Y860000D03*
X500000D03*
X480000D03*
Y880000D03*
X500000D03*
X520000D03*
X480000Y900000D03*
X500000D03*
X540000Y920000D03*
Y860000D03*
Y880000D03*
Y900000D03*
X520000Y980000D03*
X500000D03*
X480000D03*
X520000Y940000D03*
X500000D03*
X480000D03*
Y960000D03*
X500000D03*
X520000D03*
X540000Y980000D03*
Y940000D03*
Y960000D03*
X520000Y1060000D03*
X500000D03*
X480000D03*
Y1000000D03*
X500000Y1040000D03*
X520000D03*
X540000Y1060000D03*
Y1040000D03*
X480000Y1080000D03*
X500000D03*
X520000D03*
Y1120000D03*
X500000D03*
X480000D03*
X540000D03*
Y1100000D03*
X520000Y1200000D03*
X500000D03*
X480000D03*
Y1180000D03*
Y1160000D03*
X500000Y1180000D03*
Y1160000D03*
X520000Y1180000D03*
Y1160000D03*
X540000Y1180000D03*
Y1160000D03*
Y1200000D03*
X480000Y1280000D03*
X500000D03*
X520000D03*
X480000Y1260000D03*
X500000D03*
X520000D03*
X500000Y1240000D03*
X480000D03*
X540000Y1280000D03*
Y1220000D03*
X500000Y1340000D03*
X520000D03*
X480000D03*
Y1320000D03*
X500000D03*
X520000D03*
X480000Y1300000D03*
X500000D03*
X520000D03*
X540000Y1340000D03*
Y1320000D03*
Y1300000D03*
X520000Y1420000D03*
X500000D03*
X480000D03*
X520000Y1380000D03*
Y1400000D03*
X500000Y1380000D03*
Y1400000D03*
X480000Y1380000D03*
Y1400000D03*
X500000Y1360000D03*
X520000D03*
X480000D03*
X540000Y1420000D03*
Y1380000D03*
Y1400000D03*
Y1360000D03*
X520000Y1500000D03*
X500000D03*
X480000D03*
X520000Y1440000D03*
Y1460000D03*
Y1480000D03*
X500000Y1440000D03*
Y1460000D03*
Y1480000D03*
X480000Y1440000D03*
Y1460000D03*
Y1480000D03*
X540000Y1500000D03*
Y1440000D03*
Y1460000D03*
Y1480000D03*
X500000Y1560000D03*
X480000Y1520000D03*
X500000D03*
X520000D03*
X540000D03*
X480000Y1580000D03*
X540000Y1680000D03*
X520000D03*
X500000D03*
X480000D03*
Y1700000D03*
Y1660000D03*
Y1720000D03*
X500000D03*
X520000D03*
Y1700000D03*
X500000D03*
X520000Y1660000D03*
X500000D03*
X540000Y1700000D03*
Y1720000D03*
Y1660000D03*
Y1780000D03*
X520000Y1760000D03*
X480000Y1780000D03*
X500000D03*
X520000D03*
X480000Y1760000D03*
X500000D03*
X520000Y1740000D03*
X500000D03*
X480000D03*
X540000Y1760000D03*
Y1740000D03*
Y1820000D03*
Y1840000D03*
Y1860000D03*
X520000D03*
X480000D03*
X500000Y1840000D03*
X520000D03*
X500000Y1820000D03*
X480000D03*
X520000D03*
X540000Y1940000D03*
X500000D03*
X520000D03*
X480000D03*
X520000Y1920000D03*
X500000D03*
X480000D03*
X520000Y1900000D03*
X500000D03*
X480000D03*
Y1880000D03*
X500000D03*
X520000D03*
X540000Y1900000D03*
Y1880000D03*
Y1920000D03*
X492559Y1986626D03*
X512559D03*
X532559D03*
X520000Y1960000D03*
Y1980000D03*
X500000Y1960000D03*
Y1980000D03*
X480000Y1960000D03*
Y1980000D03*
X540000Y1960000D03*
Y1980000D03*
X580000Y40000D03*
X560000D03*
X600000D03*
X590018Y5500D03*
X570018D03*
X550018D03*
X580000Y20000D03*
X560000D03*
X600000D03*
X620000Y40000D03*
X610018Y5500D03*
X620000Y20000D03*
Y100000D03*
X600000D03*
X580000D03*
X560000D03*
Y120000D03*
X580000D03*
X600000D03*
X560000Y60000D03*
Y80000D03*
X580000D03*
Y60000D03*
X600000D03*
Y80000D03*
X620000Y120000D03*
Y80000D03*
Y60000D03*
X560000Y140000D03*
Y160000D03*
X580000D03*
Y140000D03*
X600000D03*
Y160000D03*
Y180000D03*
X580000D03*
X560000D03*
X620000Y160000D03*
Y140000D03*
Y180000D03*
X580000Y260000D03*
X600000D03*
X620000D03*
X560000D03*
X600000Y200000D03*
Y220000D03*
X580000D03*
Y200000D03*
X560000D03*
Y220000D03*
Y240000D03*
X580000D03*
X600000D03*
X620000D03*
Y220000D03*
Y200000D03*
X560000Y320000D03*
X580000D03*
X600000D03*
X620000D03*
X560000Y300000D03*
X580000D03*
X600000D03*
X620000D03*
X580000Y280000D03*
X600000D03*
X620000D03*
X560000D03*
X620000Y400000D03*
X600000D03*
X580000D03*
X560000D03*
Y380000D03*
X580000D03*
X600000D03*
X620000D03*
X560000Y360000D03*
X580000D03*
X600000D03*
X620000D03*
X560000Y340000D03*
X580000D03*
X600000D03*
X620000D03*
X600000Y480000D03*
X620000D03*
Y460000D03*
X580000Y440000D03*
X560000D03*
X620000Y420000D03*
X600000D03*
X580000D03*
X560000D03*
Y460000D03*
X620000Y520000D03*
X600000D03*
X580000D03*
Y500000D03*
X600000Y540000D03*
Y500000D03*
X620000D03*
X580000Y540000D03*
X560000D03*
X620000D03*
Y560000D03*
X580000D03*
X600000D03*
X560000D03*
Y580000D03*
X600000D03*
X620000Y600000D03*
X600000D03*
X580000D03*
Y580000D03*
X620000D03*
Y640000D03*
X600000D03*
X580000D03*
X560000D03*
X620000Y700000D03*
X600000D03*
X580000D03*
X560000D03*
X620000Y680000D03*
X600000D03*
X580000D03*
X560000D03*
X620000Y660000D03*
X600000D03*
X580000D03*
X560000D03*
Y740000D03*
X580000D03*
X600000D03*
X620000D03*
X580000Y760000D03*
X600000D03*
X620000D03*
X560000D03*
X580000Y780000D03*
X600000D03*
X620000D03*
X580000Y800000D03*
X600000D03*
X620000D03*
X580000Y820000D03*
X600000D03*
X620000D03*
X560000Y840000D03*
X580000D03*
X600000D03*
X560000Y780000D03*
Y800000D03*
X620000Y840000D03*
X600000Y920000D03*
X580000D03*
X560000D03*
X600000Y860000D03*
X580000D03*
X560000D03*
Y900000D03*
Y880000D03*
X580000D03*
Y900000D03*
X600000D03*
Y880000D03*
X620000Y920000D03*
Y880000D03*
Y900000D03*
Y860000D03*
X600000Y980000D03*
X580000D03*
X560000D03*
X580000Y940000D03*
X560000D03*
Y960000D03*
X580000D03*
X600000D03*
Y940000D03*
X620000D03*
Y960000D03*
Y980000D03*
X600000Y1060000D03*
X580000D03*
X560000D03*
Y1040000D03*
X580000D03*
X600000D03*
X620000D03*
Y1060000D03*
X560000Y1100000D03*
X580000D03*
X600000D03*
Y1120000D03*
X580000D03*
X560000D03*
X620000D03*
Y1100000D03*
X560000Y1180000D03*
X580000D03*
Y1160000D03*
X600000Y1180000D03*
Y1160000D03*
Y1200000D03*
X580000D03*
X560000D03*
X620000D03*
Y1160000D03*
Y1180000D03*
X580000Y1260000D03*
Y1240000D03*
X560000D03*
X600000Y1220000D03*
X580000D03*
X560000D03*
X600000Y1260000D03*
Y1240000D03*
X620000Y1280000D03*
Y1220000D03*
Y1240000D03*
Y1260000D03*
X560000Y1340000D03*
X580000D03*
X600000D03*
X560000Y1320000D03*
X580000D03*
X560000Y1300000D03*
X620000D03*
X600000Y1420000D03*
X580000D03*
X560000D03*
X600000Y1400000D03*
X580000Y1380000D03*
Y1400000D03*
X560000Y1380000D03*
Y1400000D03*
X580000Y1360000D03*
X600000D03*
X620000Y1420000D03*
Y1400000D03*
Y1380000D03*
Y1360000D03*
X600000Y1500000D03*
X580000D03*
X560000D03*
X600000Y1440000D03*
Y1460000D03*
Y1480000D03*
X580000Y1440000D03*
Y1460000D03*
Y1480000D03*
X560000Y1440000D03*
Y1460000D03*
Y1480000D03*
X620000Y1500000D03*
Y1480000D03*
Y1460000D03*
Y1440000D03*
X560000Y1520000D03*
X580000D03*
X620000Y1680000D03*
X560000D03*
X580000D03*
X600000D03*
Y1700000D03*
Y1720000D03*
X580000D03*
Y1700000D03*
X560000D03*
Y1720000D03*
X600000Y1660000D03*
X580000D03*
X560000D03*
X620000Y1700000D03*
Y1720000D03*
Y1660000D03*
Y1780000D03*
X600000D03*
X580000D03*
X560000D03*
X620000Y1760000D03*
X600000D03*
X580000D03*
X560000D03*
X620000Y1740000D03*
X600000D03*
X580000D03*
X560000D03*
Y1840000D03*
Y1860000D03*
X620000Y1800000D03*
X600000D03*
X580000D03*
X560000D03*
X620000Y1840000D03*
X600000D03*
X580000D03*
X620000Y1860000D03*
X600000D03*
X580000D03*
X560000Y1940000D03*
X580000D03*
X600000D03*
X620000D03*
X560000Y1880000D03*
X620000D03*
X600000D03*
X580000D03*
X620000Y1900000D03*
X600000D03*
X580000D03*
X620000Y1920000D03*
X600000D03*
X580000D03*
X560000D03*
Y1900000D03*
X620000Y1960000D03*
X600000D03*
X580000D03*
X552559Y1986626D03*
X572559D03*
X592559D03*
X600000Y1980000D03*
X580000D03*
X560000D03*
Y1960000D03*
X612559Y1986626D03*
X620000Y1980000D03*
X660000Y40000D03*
X640000D03*
X670018Y5500D03*
X650018D03*
X630018D03*
X660000Y20000D03*
X640000D03*
X680000D03*
Y40000D03*
X690018Y5500D03*
X680000Y100000D03*
X660000D03*
X640000D03*
Y120000D03*
X660000D03*
X640000Y60000D03*
Y80000D03*
X660000D03*
Y60000D03*
X680000Y120000D03*
Y60000D03*
Y80000D03*
X640000Y140000D03*
Y160000D03*
X660000D03*
Y140000D03*
Y180000D03*
X640000D03*
X680000Y140000D03*
Y160000D03*
Y180000D03*
X660000Y260000D03*
X640000D03*
Y240000D03*
X660000D03*
Y220000D03*
Y200000D03*
X640000Y220000D03*
Y200000D03*
X680000Y260000D03*
Y240000D03*
Y220000D03*
Y200000D03*
X640000Y320000D03*
X660000D03*
X680000D03*
X640000Y300000D03*
X660000D03*
X680000D03*
X640000Y280000D03*
X660000D03*
X680000D03*
X640000Y400000D03*
Y380000D03*
X660000D03*
X640000Y360000D03*
X660000D03*
X680000D03*
X640000Y340000D03*
X660000D03*
X680000D03*
Y480000D03*
Y460000D03*
Y440000D03*
X640000Y480000D03*
X660000D03*
Y460000D03*
X640000D03*
X660000Y440000D03*
X640000D03*
X680000Y420000D03*
X660000Y520000D03*
X640000D03*
X680000D03*
Y500000D03*
X640000D03*
X660000D03*
X640000Y540000D03*
X660000D03*
X680000D03*
Y560000D03*
X660000D03*
X640000D03*
X680000Y600000D03*
X660000D03*
X640000D03*
Y580000D03*
X660000D03*
X680000D03*
Y660000D03*
Y680000D03*
X640000Y640000D03*
Y700000D03*
X660000Y680000D03*
X640000D03*
X660000Y660000D03*
X640000D03*
X660000Y640000D03*
X680000D03*
X640000Y720000D03*
X660000D03*
X680000D03*
X640000Y740000D03*
X660000D03*
X680000D03*
X640000Y760000D03*
X660000D03*
X680000D03*
X640000Y780000D03*
X660000D03*
X680000D03*
X640000Y800000D03*
X660000D03*
X680000D03*
X640000Y820000D03*
X660000D03*
X680000D03*
X640000Y840000D03*
X660000D03*
X680000D03*
X640000Y920000D03*
X660000D03*
X640000Y900000D03*
X660000D03*
X640000Y880000D03*
X660000D03*
X640000Y860000D03*
X660000D03*
X680000Y920000D03*
Y900000D03*
Y880000D03*
Y860000D03*
X640000Y940000D03*
Y960000D03*
X660000D03*
Y980000D03*
X640000D03*
X680000D03*
Y960000D03*
X660000Y1040000D03*
X640000D03*
Y1060000D03*
X680000Y1040000D03*
X640000Y1100000D03*
Y1120000D03*
X660000D03*
Y1100000D03*
X680000D03*
Y1120000D03*
Y1080000D03*
X640000Y1200000D03*
X660000D03*
Y1160000D03*
X640000D03*
Y1180000D03*
X680000Y1160000D03*
Y1200000D03*
X640000Y1280000D03*
X660000D03*
Y1220000D03*
X640000D03*
Y1240000D03*
X660000D03*
X640000Y1260000D03*
X660000D03*
X680000Y1240000D03*
Y1260000D03*
Y1280000D03*
Y1220000D03*
X660000Y1340000D03*
X640000Y1300000D03*
X660000D03*
Y1320000D03*
X640000D03*
X680000Y1340000D03*
Y1300000D03*
Y1320000D03*
X660000Y1420000D03*
X640000D03*
Y1400000D03*
X660000D03*
X640000Y1380000D03*
X680000Y1420000D03*
Y1360000D03*
X660000Y1500000D03*
X640000D03*
X660000Y1480000D03*
X640000D03*
Y1460000D03*
Y1440000D03*
X660000D03*
X680000Y1500000D03*
Y1480000D03*
Y1440000D03*
X640000Y1680000D03*
X660000D03*
X680000D03*
Y1720000D03*
X640000Y1700000D03*
X660000D03*
Y1720000D03*
X640000D03*
Y1660000D03*
X660000D03*
X680000Y1780000D03*
X660000D03*
X640000D03*
X680000Y1760000D03*
X660000D03*
X640000D03*
X680000Y1740000D03*
X660000D03*
X640000D03*
X680000Y1820000D03*
X660000D03*
X680000Y1800000D03*
X660000D03*
X640000D03*
X680000Y1860000D03*
X660000Y1840000D03*
X640000D03*
Y1860000D03*
X660000D03*
X680000Y1880000D03*
Y1900000D03*
Y1920000D03*
X660000Y1880000D03*
X640000D03*
X660000Y1900000D03*
X640000D03*
X660000Y1920000D03*
X640000D03*
Y1940000D03*
X660000D03*
X680000Y1960000D03*
X660000D03*
X640000D03*
X632559Y1986626D03*
X652559D03*
X672559D03*
X660000Y1980000D03*
X640000D03*
X680000D03*
X692559Y1986626D03*
X700000Y20000D03*
X740000Y40000D03*
X750018Y5500D03*
X730018D03*
X710018D03*
X740000Y20000D03*
X720000D03*
X760000Y40000D03*
Y20000D03*
X700000Y120000D03*
X720000D03*
X740000D03*
X700000Y80000D03*
Y60000D03*
Y100000D03*
X720000D03*
Y60000D03*
X740000D03*
Y80000D03*
X720000D03*
X740000Y100000D03*
X760000Y120000D03*
Y100000D03*
Y80000D03*
Y60000D03*
X700000Y180000D03*
X740000D03*
X720000D03*
Y140000D03*
Y160000D03*
X760000D03*
X740000D03*
X700000D03*
Y140000D03*
X740000D03*
X760000D03*
Y180000D03*
X700000Y260000D03*
Y240000D03*
Y220000D03*
Y200000D03*
X720000Y260000D03*
Y240000D03*
Y220000D03*
Y200000D03*
X740000Y260000D03*
Y200000D03*
Y220000D03*
Y240000D03*
X760000Y260000D03*
Y200000D03*
Y220000D03*
Y240000D03*
Y320000D03*
X700000D03*
Y300000D03*
Y280000D03*
X720000Y320000D03*
Y300000D03*
Y280000D03*
X740000D03*
Y300000D03*
X760000Y280000D03*
X740000Y400000D03*
X720000D03*
X700000D03*
X740000Y380000D03*
X720000D03*
X760000Y400000D03*
Y360000D03*
Y380000D03*
Y460000D03*
Y480000D03*
X740000D03*
X720000D03*
X700000D03*
Y420000D03*
X720000D03*
X740000D03*
Y440000D03*
X720000D03*
X700000D03*
Y460000D03*
X720000D03*
X740000D03*
X760000Y420000D03*
Y440000D03*
X720000Y520000D03*
X700000D03*
X740000Y500000D03*
X720000D03*
X740000Y520000D03*
X700000Y500000D03*
Y540000D03*
X740000D03*
X720000D03*
X760000D03*
Y520000D03*
Y500000D03*
Y560000D03*
X720000D03*
X740000D03*
X700000D03*
X740000Y600000D03*
Y580000D03*
X720000D03*
X740000Y620000D03*
X720000D03*
X700000Y580000D03*
Y600000D03*
X720000D03*
X760000Y620000D03*
Y600000D03*
Y580000D03*
Y680000D03*
Y640000D03*
X740000D03*
Y680000D03*
X720000D03*
X700000D03*
Y660000D03*
X720000D03*
X740000D03*
X700000Y640000D03*
X720000D03*
X700000Y720000D03*
X720000D03*
X740000D03*
Y760000D03*
X720000D03*
X700000D03*
Y740000D03*
X720000D03*
X740000D03*
X760000Y760000D03*
Y740000D03*
Y720000D03*
X740000Y840000D03*
X700000D03*
X720000D03*
X740000Y800000D03*
X720000D03*
X700000D03*
Y820000D03*
X720000D03*
X740000D03*
X700000Y780000D03*
X720000D03*
X740000D03*
X760000Y840000D03*
Y800000D03*
Y820000D03*
Y780000D03*
X740000Y920000D03*
X700000D03*
X720000D03*
X740000Y900000D03*
Y880000D03*
Y860000D03*
X700000Y900000D03*
X720000D03*
X700000Y880000D03*
X720000D03*
X700000Y860000D03*
X720000D03*
X760000Y920000D03*
Y900000D03*
Y880000D03*
Y860000D03*
X700000Y980000D03*
X720000D03*
X740000D03*
X700000Y960000D03*
X720000D03*
X740000D03*
X760000Y980000D03*
Y960000D03*
X740000Y1040000D03*
X720000D03*
X700000D03*
X760000D03*
X700000Y1120000D03*
Y1100000D03*
X720000Y1120000D03*
X740000D03*
Y1080000D03*
X700000D03*
X760000Y1120000D03*
X740000Y1160000D03*
X720000D03*
X700000D03*
Y1200000D03*
X720000D03*
X740000D03*
X760000Y1160000D03*
Y1200000D03*
X700000Y1240000D03*
X740000Y1260000D03*
X720000D03*
X700000D03*
X740000Y1280000D03*
X720000D03*
X700000D03*
Y1220000D03*
X720000D03*
X740000D03*
Y1240000D03*
X720000D03*
X760000D03*
Y1260000D03*
Y1280000D03*
Y1220000D03*
X740000Y1340000D03*
X720000D03*
X700000D03*
X740000Y1300000D03*
X720000D03*
X700000D03*
Y1320000D03*
X740000D03*
X720000D03*
X760000Y1340000D03*
Y1300000D03*
Y1320000D03*
X740000Y1420000D03*
X720000D03*
X740000Y1380000D03*
Y1360000D03*
X720000Y1380000D03*
Y1360000D03*
X700000Y1380000D03*
Y1360000D03*
X760000Y1420000D03*
Y1380000D03*
Y1360000D03*
X700000Y1500000D03*
X740000Y1440000D03*
X720000D03*
X700000D03*
X740000Y1480000D03*
X720000D03*
X700000D03*
X760000Y1440000D03*
Y1480000D03*
X740000Y1520000D03*
X720000D03*
X760000D03*
X700000Y1680000D03*
X740000Y1700000D03*
X720000D03*
Y1720000D03*
X740000D03*
Y1680000D03*
X720000D03*
X760000Y1720000D03*
X700000Y1780000D03*
Y1760000D03*
Y1740000D03*
X720000Y1780000D03*
X740000Y1740000D03*
X760000Y1780000D03*
Y1740000D03*
X758000Y1756000D03*
X759700Y1817500D03*
X700000Y1820000D03*
Y1800000D03*
Y1860000D03*
X720000D03*
X740000D03*
X720000Y1800000D03*
X740000D03*
Y1820000D03*
X720000D03*
X759700Y1837500D03*
X720000Y1880000D03*
X740000Y1900000D03*
Y1880000D03*
X700000D03*
Y1900000D03*
Y1920000D03*
X720000Y1940000D03*
Y1900000D03*
Y1920000D03*
X700000Y1940000D03*
X760000Y1880000D03*
Y1940000D03*
X720000Y1960000D03*
X700000D03*
X720000Y1980000D03*
X700000D03*
X712559Y1986626D03*
X732559D03*
X740000Y1960000D03*
Y1980000D03*
X752559Y1986626D03*
X759900Y1959200D03*
X760000Y1980000D03*
X800000Y40000D03*
X820000D03*
X840000D03*
X780000D03*
X810018Y5500D03*
X790018D03*
X770018D03*
X780000Y20000D03*
X800000D03*
X820000D03*
X830018Y5500D03*
X840000Y20000D03*
X800000Y120000D03*
X820000D03*
X840000D03*
X800000Y100000D03*
X820000D03*
X840000D03*
X800000Y80000D03*
X820000D03*
X840000D03*
X800000Y60000D03*
X820000D03*
X840000D03*
X780000Y120000D03*
Y60000D03*
Y80000D03*
Y100000D03*
Y160000D03*
X840000Y140000D03*
X820000D03*
X800000D03*
X816000Y187000D03*
X780000Y140000D03*
Y180000D03*
X828500Y171000D03*
X840000Y174250D03*
X820500Y171000D03*
X820000Y260000D03*
X780000Y200000D03*
Y220000D03*
Y240000D03*
X800000Y220000D03*
Y240000D03*
X820000Y220000D03*
X840000Y240000D03*
X828000Y203000D03*
X780000Y300000D03*
X800000Y280000D03*
Y340000D03*
X780000D03*
Y380000D03*
Y360000D03*
Y400000D03*
X820000D03*
X800000D03*
Y380000D03*
Y360000D03*
X840000Y400000D03*
X780000Y440000D03*
Y420000D03*
Y460000D03*
X800000Y480000D03*
X820000Y420000D03*
Y440000D03*
Y460000D03*
X800000D03*
Y440000D03*
Y420000D03*
X820000Y480000D03*
X780000D03*
X840000D03*
Y420000D03*
Y440000D03*
Y460000D03*
X780000Y540000D03*
X800000D03*
X820000D03*
X780000Y500000D03*
X820000D03*
Y520000D03*
X800000Y500000D03*
Y520000D03*
X780000D03*
X840000Y500000D03*
Y520000D03*
Y540000D03*
X780000Y580000D03*
Y560000D03*
X800000Y600000D03*
Y580000D03*
Y560000D03*
X780000Y620000D03*
X800000D03*
X820000D03*
X780000Y600000D03*
X820000Y580000D03*
Y560000D03*
Y600000D03*
X840000Y620000D03*
Y580000D03*
Y560000D03*
Y600000D03*
X820000Y700000D03*
X780000D03*
X778400Y659800D03*
X800000Y640000D03*
X780000D03*
X820000Y660000D03*
X798400Y659800D03*
X840000Y640000D03*
Y680000D03*
Y660000D03*
Y700000D03*
X820000Y720000D03*
X800000Y760000D03*
X780000D03*
Y740000D03*
X800000D03*
Y720000D03*
X780000D03*
X840000D03*
X780000Y840000D03*
X800000D03*
X820000D03*
Y820000D03*
X780000Y800000D03*
Y780000D03*
X800000D03*
X840000Y840000D03*
Y800000D03*
Y820000D03*
X780000Y920000D03*
X800000D03*
X820000D03*
X780000Y900000D03*
X800000D03*
X820000D03*
X780000Y880000D03*
X800000D03*
X820000D03*
X780000Y860000D03*
X800000D03*
X820000D03*
X840000Y920000D03*
Y860000D03*
Y880000D03*
Y900000D03*
X780000Y980000D03*
X800000D03*
X820000D03*
X780000Y960000D03*
X800000D03*
X820000D03*
X840000D03*
Y980000D03*
X800000Y1060000D03*
X820000D03*
X780000D03*
X820000Y1040000D03*
X840000Y1060000D03*
Y1040000D03*
X780000Y1120000D03*
X800000D03*
Y1080000D03*
Y1100000D03*
X820000Y1120000D03*
X800000Y1200000D03*
X820000D03*
X780000Y1160000D03*
X800000D03*
X780000Y1200000D03*
X840000D03*
X820000Y1220000D03*
Y1240000D03*
X800000D03*
X780000D03*
X820000Y1260000D03*
X800000D03*
X780000D03*
X820000Y1280000D03*
X800000D03*
X780000D03*
Y1220000D03*
X800000D03*
X840000Y1280000D03*
Y1220000D03*
Y1240000D03*
Y1260000D03*
X820000Y1340000D03*
X800000D03*
X780000D03*
X820000Y1300000D03*
X800000D03*
X780000D03*
Y1320000D03*
X820000D03*
X800000D03*
X840000Y1340000D03*
Y1300000D03*
Y1320000D03*
X820000Y1420000D03*
X800000D03*
X780000D03*
X820000Y1380000D03*
Y1360000D03*
X800000Y1380000D03*
Y1360000D03*
X780000Y1380000D03*
Y1360000D03*
X840000Y1420000D03*
Y1360000D03*
Y1380000D03*
X820000Y1440000D03*
X800000D03*
X780000D03*
X820000Y1480000D03*
X800000D03*
X780000D03*
X840000Y1440000D03*
Y1480000D03*
X800000Y1560000D03*
X780000Y1520000D03*
X840000Y1640000D03*
Y1600000D03*
X820000Y1680000D03*
X840000D03*
Y1660000D03*
X780000Y1780000D03*
X800000D03*
Y1740000D03*
X780000D03*
X795500Y1755000D03*
X837500Y1785000D03*
X829500D03*
X819000D03*
X816000Y1801000D03*
X780000Y1800000D03*
X800000D03*
X780000Y1840000D03*
X800000Y1820000D03*
X820000D03*
X828000Y1862000D03*
X827500Y1817000D03*
X800000Y1920000D03*
X820000D03*
X780000D03*
X820000Y1980000D03*
X772559Y1986626D03*
X792559D03*
X812559D03*
X769239Y1955776D03*
X780000Y1980000D03*
X800000D03*
X823400Y1973400D03*
X827900D03*
X835900Y1973500D03*
X839400D03*
X832559Y1986626D03*
X840000Y1980000D03*
X799205Y1960532D03*
X860000Y40000D03*
X880000D03*
X890018Y5500D03*
X870018D03*
X850018D03*
X880000Y20000D03*
X860000D03*
X900000Y40000D03*
X910018Y5500D03*
X900000Y20000D03*
X860000Y120000D03*
X880000D03*
X860000Y100000D03*
X880000D03*
X860000Y80000D03*
X880000D03*
X860000Y60000D03*
X880000D03*
X900000Y120000D03*
Y60000D03*
Y100000D03*
Y80000D03*
X860000Y140000D03*
X908493Y136513D03*
X880000Y180000D03*
X869250Y144750D03*
X885993Y134893D03*
X860000Y260000D03*
Y240000D03*
X908654Y231105D03*
X904838D03*
X872500Y241500D03*
X860100Y336500D03*
X873600Y332200D03*
X860100Y333000D03*
X901500Y312500D03*
X856200Y337300D03*
X865000Y371000D03*
X868500D03*
X876000D03*
X872500D03*
X879600Y385200D03*
X860000Y400000D03*
X880000D03*
X900000D03*
X899900Y382300D03*
X850966Y370025D03*
X880000Y480000D03*
X860000D03*
X880000Y420000D03*
X860000D03*
X880000Y440000D03*
X860000D03*
X880000Y460000D03*
X860000D03*
X900000Y480000D03*
Y420000D03*
Y440000D03*
Y460000D03*
X907493Y542025D03*
X880000Y500000D03*
X860000D03*
X880000Y520000D03*
X860000D03*
X900000Y500000D03*
Y520000D03*
X872875Y535275D03*
X891250Y537500D03*
X860000Y580000D03*
Y560000D03*
X880000Y580000D03*
Y600000D03*
X860000D03*
X900000D03*
X908654Y636613D03*
X904838D03*
X868500Y654000D03*
X859500Y741800D03*
X873400Y738400D03*
X859500Y738300D03*
X901500Y718000D03*
X856100Y743300D03*
X850966Y775525D03*
X860000Y840000D03*
X880000D03*
X864500Y776500D03*
X868000D03*
X872000D03*
X875500D03*
X860000Y800000D03*
X880000D03*
X860000Y820000D03*
X880000D03*
X900000Y840000D03*
Y800000D03*
Y820000D03*
X860000Y920000D03*
X880000D03*
X860000Y860000D03*
X880000D03*
X860000Y880000D03*
X880000D03*
X860000Y900000D03*
X880000D03*
X900000Y920000D03*
Y860000D03*
Y880000D03*
Y900000D03*
X907493Y947537D03*
X860000Y980000D03*
X886517Y945917D03*
X872875Y940925D03*
X880000Y1000000D03*
X860000Y1040000D03*
X908654Y1042129D03*
X904838D03*
X900000Y1000000D03*
Y1040000D03*
Y1020000D03*
X868500Y1059500D03*
X900000Y1080000D03*
X901500Y1123500D03*
X859500Y1147600D03*
X874200Y1144000D03*
X859500Y1144100D03*
X864000Y1181900D03*
X867500D03*
X872200D03*
X875700D03*
X860000Y1200000D03*
X880000D03*
X900000D03*
X854500Y1148700D03*
X850600Y1181025D03*
X860000Y1280000D03*
X880000D03*
X860000Y1220000D03*
Y1240000D03*
Y1260000D03*
X880000Y1220000D03*
Y1240000D03*
Y1260000D03*
X900000Y1280000D03*
Y1220000D03*
Y1240000D03*
Y1260000D03*
X907493Y1353048D03*
X880000Y1340000D03*
X860000D03*
Y1300000D03*
Y1320000D03*
X880000D03*
Y1300000D03*
X900000Y1320000D03*
Y1300000D03*
X872875Y1346488D03*
X891250Y1348500D03*
X860000Y1420000D03*
Y1380000D03*
Y1440000D03*
X908654Y1447641D03*
X904838D03*
X868500Y1465000D03*
X859500Y1553200D03*
X873300Y1549100D03*
X859500Y1549700D03*
X901500Y1529000D03*
X855500Y1554300D03*
X860000Y1640000D03*
Y1580000D03*
X865500Y1589000D03*
X869000D03*
X873000D03*
X876500D03*
X880000Y1599000D03*
X900000Y1600000D03*
X850966Y1586525D03*
X891500Y1712000D03*
X895500D03*
Y1708000D03*
X860000Y1660000D03*
X885750Y1701500D03*
X891500Y1708000D03*
X886600Y1756100D03*
X872875Y1751600D03*
X906500Y1734100D03*
X907493Y1758560D03*
X860000Y1860000D03*
X908654Y1853153D03*
X904838D03*
X860000Y1880000D03*
X901500Y1934500D03*
X867500Y1870000D03*
X843500Y1973500D03*
X847000D03*
X852559Y1986626D03*
X872559D03*
X896546Y1986566D03*
X860000Y1980000D03*
X912559Y1986626D03*
X844800Y1949700D03*
X858800Y1951300D03*
X960000Y40000D03*
X940000D03*
X920000D03*
X950018Y5500D03*
X930018D03*
X920000Y20000D03*
X940000D03*
X960000D03*
X980000Y40000D03*
X970018Y5500D03*
X980000Y20000D03*
X960000Y120000D03*
X940000D03*
X920000D03*
Y60000D03*
X940000D03*
X960000D03*
X920000Y100000D03*
X940000D03*
X960000D03*
Y80000D03*
X940000D03*
X920000D03*
X980000Y120000D03*
Y60000D03*
Y100000D03*
Y80000D03*
X987992Y163376D03*
X960000Y140000D03*
X940000D03*
X960000Y160000D03*
X940000D03*
Y180000D03*
X960000D03*
X980000D03*
X921400Y245200D03*
X940000Y200000D03*
X960000D03*
Y220000D03*
X940000D03*
Y240000D03*
X960000D03*
Y260000D03*
X940000D03*
X980000Y240000D03*
Y260000D03*
Y200000D03*
Y220000D03*
X940000Y280000D03*
X920000D03*
X960000D03*
X920000Y300000D03*
X940000D03*
X960000D03*
X920000Y320000D03*
X940000D03*
X960000D03*
X980000Y280000D03*
Y300000D03*
Y320000D03*
X960000Y400000D03*
X940000D03*
X920000D03*
X960000Y340000D03*
X940000D03*
X920000D03*
Y360000D03*
X940000D03*
X960000D03*
Y380000D03*
X940000D03*
X920000D03*
X980000Y400000D03*
Y340000D03*
Y360000D03*
Y380000D03*
X920000Y480000D03*
X940000D03*
X960000D03*
X920000Y420000D03*
X940000D03*
X960000D03*
X920000Y440000D03*
X940000D03*
X960000D03*
X920000Y460000D03*
X940000D03*
X960000D03*
X980000Y480000D03*
Y420000D03*
Y440000D03*
Y460000D03*
X920000Y500000D03*
X940000D03*
X960000D03*
X920000Y520000D03*
X940000D03*
X960000D03*
Y540000D03*
X980000Y500000D03*
Y520000D03*
Y540000D03*
X940000Y620000D03*
X960000D03*
Y560000D03*
Y580000D03*
Y600000D03*
X940000Y580000D03*
Y600000D03*
X920000Y580000D03*
Y600000D03*
X980000Y620000D03*
Y560000D03*
Y580000D03*
Y600000D03*
X987992Y686998D03*
X920000Y700000D03*
X919000Y651511D03*
X940000Y640000D03*
X960000D03*
X920000Y680000D03*
X940000D03*
X960000D03*
Y660000D03*
X940000D03*
X920000D03*
X940000Y700000D03*
X960000D03*
X980000Y640000D03*
Y660000D03*
Y700000D03*
X940000Y760000D03*
X960000D03*
X920000D03*
Y740000D03*
Y720000D03*
X940000D03*
X960000D03*
X940000Y740000D03*
X960000D03*
X980000Y760000D03*
Y720000D03*
Y740000D03*
X940000Y840000D03*
X960000D03*
X920000D03*
X940000Y780000D03*
X960000D03*
X940000Y800000D03*
X960000D03*
X940000Y820000D03*
X960000D03*
X920000Y800000D03*
Y820000D03*
Y780000D03*
X980000Y840000D03*
Y780000D03*
Y800000D03*
Y820000D03*
X940000Y920000D03*
X960000D03*
X920000D03*
X940000Y860000D03*
X960000D03*
X940000Y880000D03*
X960000D03*
X940000Y900000D03*
X960000D03*
X920000Y860000D03*
Y880000D03*
Y900000D03*
X980000Y920000D03*
Y860000D03*
Y880000D03*
Y900000D03*
X960000Y980000D03*
Y940000D03*
X940000D03*
X960000Y960000D03*
X980000Y980000D03*
Y940000D03*
Y960000D03*
X922900Y1054200D03*
X920000Y1060000D03*
X940000D03*
X960000D03*
Y1000000D03*
X940000D03*
X920000D03*
Y1020000D03*
X940000D03*
X960000D03*
Y1040000D03*
X940000D03*
X920000D03*
X980000Y1000000D03*
Y1020000D03*
Y1040000D03*
X987992Y1082667D03*
X940000Y1140000D03*
X960000D03*
X920000Y1080000D03*
X940000D03*
X960000D03*
Y1100000D03*
X940000D03*
X920000Y1120000D03*
X940000D03*
X960000D03*
X920000Y1140000D03*
X980000D03*
Y1100000D03*
X979962Y1075211D03*
X980000Y1120000D03*
X923000Y1160200D03*
X940000Y1160000D03*
X960000D03*
Y1180000D03*
X940000D03*
X923000Y1180200D03*
X960000Y1200000D03*
X940000D03*
X920000D03*
X980000Y1160000D03*
Y1180000D03*
Y1200000D03*
X960000Y1280000D03*
X940000D03*
X920000D03*
X960000Y1220000D03*
X940000D03*
X960000Y1240000D03*
X940000D03*
X960000Y1260000D03*
X940000D03*
X920000Y1220000D03*
Y1240000D03*
Y1260000D03*
X980000Y1220000D03*
Y1240000D03*
Y1260000D03*
Y1280000D03*
X960000Y1340000D03*
X940000D03*
X920000D03*
X960000Y1300000D03*
X940000D03*
X960000Y1320000D03*
X940000D03*
X920000Y1300000D03*
Y1320000D03*
X980000Y1340000D03*
Y1300000D03*
Y1320000D03*
X981700Y1409000D03*
X954300Y1412600D03*
X960000Y1360000D03*
Y1380000D03*
Y1400000D03*
X940000D03*
X920000D03*
X963500Y1409000D03*
X973000D03*
X968000D03*
X977500D03*
X980000Y1360000D03*
Y1380000D03*
Y1400000D03*
X919000Y1462540D03*
X920000Y1480000D03*
Y1440000D03*
X965000Y1525000D03*
X955000D03*
X945000D03*
Y1516000D03*
X955000D03*
X965000D03*
X935000Y1555000D03*
X945000D03*
X955000D03*
X965000D03*
X920000Y1520000D03*
Y1540000D03*
X935000Y1575000D03*
Y1565000D03*
X945000Y1575000D03*
X955000D03*
X965000D03*
Y1565000D03*
X955000D03*
X945000D03*
X923800Y1559300D03*
X935000Y1545000D03*
Y1535000D03*
Y1525000D03*
Y1516000D03*
X965000Y1545000D03*
X955000D03*
X945000D03*
Y1535000D03*
X955000D03*
X965000D03*
X975000Y1565000D03*
Y1575000D03*
Y1525000D03*
Y1535000D03*
Y1545000D03*
Y1555000D03*
X965000Y1605000D03*
X935000Y1595000D03*
Y1585000D03*
X945000Y1595000D03*
X955000D03*
X965000D03*
Y1585000D03*
X955000D03*
X945000D03*
X923500Y1579800D03*
X920000Y1600000D03*
X975000Y1595000D03*
Y1605000D03*
Y1585000D03*
X960000Y1700000D03*
Y1720000D03*
X933000Y1704000D03*
X951500Y1658000D03*
X952000Y1678000D03*
X980000Y1700000D03*
Y1720000D03*
X963500Y1675000D03*
Y1657000D03*
X960000Y1740000D03*
Y1760000D03*
X940000D03*
X933000Y1736500D03*
X925500Y1738000D03*
X960000Y1780000D03*
X980000D03*
Y1740000D03*
Y1760000D03*
X960000Y1860000D03*
X940000D03*
X960000Y1800000D03*
X940000D03*
X920000D03*
X940000Y1820000D03*
X960000D03*
X940000Y1840000D03*
X960000D03*
X920000D03*
X980000Y1860000D03*
Y1800000D03*
Y1820000D03*
Y1840000D03*
X987992Y1903534D03*
X920000Y1920000D03*
X940000D03*
X960000D03*
Y1940000D03*
X940000D03*
X920000D03*
X919000Y1868047D03*
X960000Y1880000D03*
X940000D03*
X920000D03*
X960000Y1900000D03*
X940000D03*
X920000D03*
X980000Y1920000D03*
Y1940000D03*
X980018Y1897856D03*
X932559Y1986626D03*
X952559D03*
X960000Y1960000D03*
X940000D03*
X920000D03*
Y1980000D03*
X940000D03*
X960000D03*
X972559Y1986626D03*
X980000Y1960000D03*
Y1980000D03*
X1031902Y43616D03*
X1020000Y40000D03*
X1000000D03*
X1031902Y23616D03*
X1030018Y5500D03*
X1010018D03*
X990018D03*
X1000000Y20000D03*
X1020000D03*
Y120000D03*
X1000000D03*
X1031902Y63616D03*
Y103616D03*
Y83616D03*
X1000000Y60000D03*
X1020000D03*
X1000000Y100000D03*
X1020000D03*
Y80000D03*
X1000000D03*
X989330Y168376D03*
X992992Y172077D03*
X1003031D03*
X1006732Y168376D03*
X1008070Y163376D03*
X1031902Y143616D03*
Y123616D03*
Y163616D03*
X1020000Y140000D03*
Y160000D03*
Y180000D03*
X1031902Y183616D03*
X1000000Y240000D03*
X1020000D03*
X1031902Y263616D03*
X1020000Y260000D03*
X1000000D03*
X1031902Y223616D03*
Y203616D03*
Y243616D03*
X1000000Y200000D03*
X1020000D03*
Y220000D03*
X1000000D03*
X1031902Y303616D03*
Y283616D03*
Y323616D03*
X1000000Y280000D03*
X1020000D03*
X1000000Y300000D03*
X1020000D03*
X1000000Y320000D03*
X1020000D03*
X1031902Y403616D03*
X1020000Y400000D03*
X1000000D03*
X1031902Y383616D03*
Y363616D03*
Y343616D03*
X1020000Y340000D03*
X1000000D03*
Y360000D03*
X1020000D03*
Y380000D03*
X1000000D03*
X1031902Y483616D03*
X1000000Y480000D03*
X1020000D03*
X1031902Y443616D03*
Y423616D03*
Y463616D03*
X1000000Y420000D03*
X1020000D03*
X1000000Y440000D03*
X1020000D03*
X1000000Y460000D03*
X1020000D03*
X1031902Y523616D03*
Y503616D03*
Y543616D03*
X1000000Y500000D03*
X1020000D03*
X1000000Y520000D03*
X1020000D03*
X1000000Y540000D03*
X1020000D03*
X1031902Y623616D03*
X1000000Y620000D03*
X1020000D03*
X1031902Y603616D03*
Y583616D03*
Y563616D03*
X1020000Y560000D03*
X1000000D03*
X1020000Y580000D03*
X1000000D03*
X1020000Y600000D03*
X1000000D03*
X989330Y691998D03*
X992992Y695699D03*
X1003031D03*
X1006732Y691998D03*
X1008070Y686998D03*
X1031902Y683616D03*
Y663616D03*
Y643616D03*
X1000000Y640000D03*
X1020000D03*
Y660000D03*
Y680000D03*
Y700000D03*
X1000000Y740000D03*
X1020000D03*
X1000000Y760000D03*
X1020000D03*
X1031902Y763616D03*
Y743616D03*
Y723616D03*
Y703616D03*
X1000000Y720000D03*
X1020000D03*
X1031902Y843616D03*
X1000000Y840000D03*
X1020000D03*
X1031902Y823616D03*
Y803616D03*
Y783616D03*
X1000000Y780000D03*
X1020000D03*
X1000000Y800000D03*
X1020000D03*
X1000000Y820000D03*
X1020000D03*
X1000000Y920000D03*
X1020000D03*
X1031902Y903616D03*
Y883616D03*
Y863616D03*
X1000000Y860000D03*
X1020000D03*
X1000000Y880000D03*
X1020000D03*
X1000000Y900000D03*
X1020000D03*
X1031902Y983616D03*
X1000000Y980000D03*
X1020000D03*
X1031902Y963616D03*
Y943616D03*
Y923616D03*
X1020000Y940000D03*
X1000000D03*
Y960000D03*
X1020000D03*
X1031902Y1063616D03*
X1020000Y1060000D03*
X1031902Y1043616D03*
Y1023616D03*
Y1003616D03*
X1020000Y1000000D03*
X1000000D03*
Y1020000D03*
X1020000D03*
Y1040000D03*
X1000000D03*
X989330Y1087667D03*
X992992Y1091368D03*
X1003031D03*
X1006732Y1087667D03*
X1008070Y1082667D03*
X1031902Y1123616D03*
X1000000Y1140000D03*
X1020000D03*
X1031902Y1103616D03*
Y1083616D03*
X1020000Y1080000D03*
Y1100000D03*
X999922Y1102598D03*
X1000000Y1120000D03*
X1020000D03*
X1031902Y1143616D03*
Y1183616D03*
Y1163616D03*
X1000000Y1160000D03*
X1020000D03*
Y1180000D03*
X1000000D03*
X1031902Y1203616D03*
X1020000Y1200000D03*
X1000000D03*
Y1220000D03*
X1020000Y1240000D03*
X1000000D03*
X1020000Y1260000D03*
X1000000D03*
X1031902Y1283616D03*
X1020000Y1280000D03*
X1000000D03*
X1031902Y1263616D03*
Y1243616D03*
Y1223616D03*
X1020000Y1220000D03*
X1031902Y1343616D03*
X1020000Y1340000D03*
X1000000D03*
X1031902Y1323616D03*
Y1303616D03*
X1020000Y1300000D03*
X1000000D03*
X1020000Y1320000D03*
X1000000D03*
X986200Y1409000D03*
X994600Y1414100D03*
X990300Y1412500D03*
X1031902Y1363616D03*
Y1383616D03*
X1020000Y1360000D03*
X1000000D03*
Y1380000D03*
X1020000D03*
Y1400000D03*
X1000000D03*
X994898Y1646102D03*
X992500Y1636000D03*
X991602Y1622500D03*
X1000000Y1700000D03*
X1020000Y1720000D03*
X1000000D03*
X995102Y1676102D03*
X995000Y1656102D03*
Y1666102D03*
X1031902Y1785969D03*
X1000000Y1780000D03*
X1020000D03*
X1031902Y1745969D03*
Y1725969D03*
Y1765969D03*
X1000000Y1740000D03*
X1020000D03*
Y1760000D03*
X1000000D03*
X1031902Y1865969D03*
Y1845969D03*
X1020000Y1860000D03*
X1000000D03*
X1031902Y1805969D03*
Y1825969D03*
X1020000Y1800000D03*
X1000000D03*
Y1820000D03*
X1020000D03*
X1000000Y1840000D03*
X1020000D03*
X989330Y1908534D03*
X992992Y1912235D03*
X1003031D03*
X1006732Y1908534D03*
X1008070Y1903534D03*
X1031902Y1925969D03*
X999469Y1923465D03*
X1020000Y1920000D03*
Y1940000D03*
X1000000D03*
X1031902Y1885969D03*
Y1905969D03*
X1020000Y1880000D03*
Y1900000D03*
X1031902Y1965969D03*
Y1945969D03*
X992559Y1986626D03*
X1012559D03*
X1031902Y1985969D03*
X1020000Y1960000D03*
X1000000D03*
Y1980000D03*
X1020000D03*
G54D20*
X31981Y1768323D03*
X135064Y213390D03*
X134941Y264178D03*
X135095Y288972D03*
X134995Y301768D03*
X135095Y625402D03*
X158500Y569500D03*
X134941Y669690D03*
X135095Y694484D03*
X134993Y707280D03*
X135095Y1030914D03*
X134941Y1075202D03*
X135095Y1099996D03*
X135001Y1112792D03*
X135095Y1436426D03*
X134935Y1480714D03*
X135095Y1505508D03*
X134995Y1518304D03*
X153700Y1633600D03*
X135065Y1835438D03*
X134895Y1905020D03*
X863441Y219890D03*
X863307Y269678D03*
X863441Y288972D03*
X863346Y301768D03*
X863441Y625402D03*
Y694484D03*
X863287Y669690D03*
X863397Y713280D03*
X863441Y1030914D03*
X863346Y1112792D03*
X863441Y1099996D03*
X863308Y1080702D03*
X863286Y1480714D03*
X863441Y1436426D03*
X863347Y1518304D03*
X863441Y1505508D03*
Y1841938D03*
X863346Y1923816D03*
X863441Y1911020D03*
X863287Y1886226D03*
G54D23*
X82087Y28858D03*
Y178464D03*
Y434370D03*
Y583976D03*
Y839882D03*
Y989488D03*
Y1245394D03*
Y1395000D03*
Y1650906D03*
Y1800512D03*
X162008Y191614D03*
Y341220D03*
Y597126D03*
Y746732D03*
Y1002638D03*
Y1152244D03*
Y1408150D03*
Y1557756D03*
Y1813662D03*
Y1963268D03*
X890354Y191614D03*
Y341220D03*
Y597126D03*
Y746732D03*
Y1002638D03*
Y1152244D03*
Y1408150D03*
Y1557756D03*
Y1813662D03*
Y1963268D03*
G54D10*
X-63741Y15000D03*
X-42339Y1008909D03*
X-63741Y1977126D03*
X25499Y1950499D03*
X1010999Y43999D03*
X1010499Y1950499D03*
X1101142Y15000D03*
Y1977126D03*
G54D14*
X11811Y571426D03*
Y949378D03*
Y1067489D03*
Y1484811D03*
Y1445441D03*
Y1862763D03*
G54D18*
X33469Y1029523D03*
X269690Y1490152D03*
G54D28*
X1023228Y1416024D03*
Y1694212D03*
G36*
G01X43453Y275788D02*
G02X23476I-9988J-8073D01*
G03X24559Y278851I-3790J3063D01*
G01Y281496D01*
G02X42370I8906J0D01*
G01Y278851D01*
G03X43453Y275788I4873J0D01*
G37*
G36*
G01X31642Y1917127D02*
G02X11665I-9989J-8073D01*
G03X12748Y1920190I-3790J3063D01*
G01Y1922835D01*
G02X30559I8906J0D01*
G01Y1920190D01*
G03X31642Y1917127I4873J0D01*
G37*
G36*
G01X143846Y12009D02*
G02X123869I-9988J-8073D01*
G03X124952Y15072I-3790J3063D01*
G01Y17717D01*
G02X142763I8905J0D01*
G01Y15072D01*
G03X143846Y12009I4873J0D01*
G37*
G36*
G01X285579Y273820D02*
G02X265602I-9988J-8073D01*
G03X266685Y276883I-3790J3063D01*
G01Y279528D01*
G02X284496I8906J0D01*
G01Y276883D01*
G03X285579Y273820I4873J0D01*
G37*
G36*
G01Y679322D02*
G02X265602I-9988J-8073D01*
G03X266685Y682385I-3790J3063D01*
G01Y685030D01*
G02X284496I8906J0D01*
G01Y682385D01*
G03X285579Y679322I4873J0D01*
G37*
G36*
G01Y1082865D02*
G02X265602I-9988J-8073D01*
G03X266685Y1085928I-3790J3063D01*
G01Y1088573D01*
G02X284496I8906J0D01*
G01Y1085928D01*
G03X285579Y1082865I4873J0D01*
G37*
G36*
G01Y1897826D02*
G02X265602I-9988J-8073D01*
G03X266685Y1900889I-3790J3063D01*
G01Y1903534D01*
G02X284496I8906J0D01*
G01Y1900889D01*
G03X285579Y1897826I4873J0D01*
G37*
G36*
G01X1008019Y157668D02*
G02X988042I-9989J-8073D01*
G03X989125Y160731I-3790J3063D01*
G01Y163376D01*
G02X1006936I8906J0D01*
G01Y160731D01*
G03X1008019Y157668I4873J0D01*
G37*
G36*
G01Y681290D02*
G02X988042I-9989J-8073D01*
G03X989125Y684353I-3790J3063D01*
G01Y686998D01*
G02X1006936I8906J0D01*
G01Y684353D01*
G03X1008019Y681290I4873J0D01*
G37*
G36*
G01Y1076959D02*
G02X988042I-9989J-8073D01*
G03X989125Y1080022I-3790J3063D01*
G01Y1082667D01*
G02X1006936I8906J0D01*
G01Y1080022D01*
G03X1008019Y1076959I4873J0D01*
G37*
G36*
G01Y1897826D02*
G02X988042I-9989J-8073D01*
G03X989125Y1900889I-3790J3063D01*
G01Y1903534D01*
G02X1006936I8906J0D01*
G01Y1900889D01*
G03X1008019Y1897826I4873J0D01*
G37*
G54D13*
X27500Y380000D03*
X27000Y440000D03*
X27500Y540000D03*
Y553500D03*
X34000Y1321000D03*
X21000Y1424500D03*
X22000Y1487000D03*
X37000Y1443500D03*
X30500Y1463500D03*
X71000Y58000D03*
X97000Y296500D03*
X111500Y276000D03*
X84500Y315000D03*
X67000Y269000D03*
X66512Y287899D03*
X46487Y360400D03*
X48822Y393916D03*
X100400Y406000D03*
X104400D03*
X107900D03*
X96900D03*
X51500Y469000D03*
X112600Y442500D03*
X98300Y443400D03*
X71000Y463500D03*
X112600Y439000D03*
X99900Y582400D03*
X61900Y584300D03*
X72900Y605400D03*
X94700Y599800D03*
X59000Y659500D03*
X49000Y638000D03*
X76500Y665000D03*
X62000Y736500D03*
X61500Y748000D03*
X51500Y730500D03*
Y757500D03*
X63100Y788800D03*
X73500Y779500D03*
X100600Y811300D03*
X104600D03*
X108100D03*
X97100D03*
X112500Y848700D03*
Y845200D03*
X98300Y850400D03*
X71000Y869000D03*
X75000Y1182500D03*
X41500Y1165500D03*
Y1178000D03*
X67500Y1191500D03*
X81500Y1213000D03*
X99100Y1219800D03*
X104500Y1217000D03*
X108000D03*
X95700Y1219700D03*
X112600Y1254300D03*
X98300Y1255900D03*
X71000Y1274500D03*
X112600Y1250800D03*
X64000Y1328500D03*
X58500Y1320500D03*
X48000Y1482000D03*
Y1505500D03*
X91125Y1565900D03*
X100500Y1622500D03*
X104500D03*
X108000D03*
X97000D03*
X98600Y1659800D03*
X71000Y1680000D03*
X170034Y31475D03*
X135500Y200500D03*
X125500Y265500D03*
X132500Y236000D03*
X128500Y248000D03*
X135064Y219602D03*
X171595Y203917D03*
X148095Y211771D03*
X171595Y218917D03*
X148095Y221220D03*
X171595Y233917D03*
X148095Y230669D03*
Y236968D03*
Y246417D03*
Y255866D03*
Y262165D03*
X126000Y293000D03*
X125000Y312000D03*
X134941Y269602D03*
X135095Y282602D03*
X134995Y307602D03*
X148095Y271614D03*
Y281063D03*
Y290511D03*
Y299960D03*
Y309409D03*
Y318858D03*
X171595Y278917D03*
Y283917D03*
X119159Y405100D03*
X163500Y423000D03*
X135095Y618614D03*
X171595Y609429D03*
X148095Y617283D03*
X171595Y624429D03*
X148095Y626732D03*
X134941Y675114D03*
X135095Y688114D03*
X171895Y639429D03*
X148095Y636181D03*
Y642480D03*
Y651929D03*
Y661378D03*
Y667677D03*
Y677126D03*
Y686575D03*
Y696023D03*
X171595Y684429D03*
Y689429D03*
X134993Y713114D03*
X148095Y705472D03*
Y714921D03*
Y724370D03*
X119534Y810975D03*
X135095Y1024126D03*
X171595Y1014941D03*
X148095Y1022795D03*
X171595Y1029941D03*
X148095Y1032244D03*
X171595Y1044941D03*
X148095Y1041693D03*
Y1047992D03*
Y1057441D03*
Y1066890D03*
X134941Y1080626D03*
X135095Y1093626D03*
X135001Y1118626D03*
X148095Y1073189D03*
Y1082638D03*
Y1092087D03*
Y1101535D03*
Y1110984D03*
Y1120433D03*
Y1129882D03*
X171595Y1089941D03*
Y1094941D03*
X119534Y1216475D03*
X135095Y1429638D03*
X171595Y1420453D03*
X148095Y1428307D03*
X134935Y1486138D03*
X135095Y1499138D03*
X171595Y1435453D03*
X148095Y1437756D03*
X171895Y1450453D03*
X148095Y1447205D03*
Y1453504D03*
Y1462953D03*
Y1472402D03*
Y1478701D03*
Y1488150D03*
Y1497599D03*
X171595Y1495453D03*
Y1500453D03*
X134995Y1524138D03*
X148095Y1507047D03*
Y1516496D03*
Y1525945D03*
Y1535394D03*
X119534Y1621975D03*
X113200Y1659800D03*
Y1656300D03*
X135065Y1841650D03*
X171595Y1825965D03*
X148095Y1833819D03*
X171595Y1840965D03*
X148095Y1843268D03*
X171595Y1855965D03*
X148095Y1852717D03*
Y1859016D03*
X134895Y1886150D03*
Y1891650D03*
Y1910650D03*
X134995Y1923650D03*
Y1929650D03*
X148095Y1868465D03*
Y1877914D03*
Y1884213D03*
Y1893662D03*
Y1903111D03*
Y1912559D03*
Y1922008D03*
Y1931457D03*
X171595Y1900965D03*
Y1905965D03*
X148095Y1940906D03*
X190500Y639713D03*
X370128Y361337D03*
X349706Y355693D03*
X356250Y349000D03*
X368500Y364500D03*
X372000D03*
X383750Y349000D03*
X391800Y355800D03*
X362000Y797000D03*
X365500D03*
X358000Y794000D03*
X377250Y779000D03*
X385250Y785700D03*
X371000Y1168000D03*
X367500D03*
X363500Y1165000D03*
X383750Y1150500D03*
X391765Y1157852D03*
X348250Y1649000D03*
X368500Y1664000D03*
X372500Y1667000D03*
X376000D03*
X356238Y1655722D03*
X876441Y262165D03*
Y255866D03*
X863307Y264102D03*
X876441Y246417D03*
Y236968D03*
Y230669D03*
Y221220D03*
Y211771D03*
X863441Y213102D03*
X899941Y233917D03*
Y218917D03*
Y203917D03*
X876441Y318858D03*
Y309409D03*
Y299960D03*
Y290511D03*
Y281063D03*
Y271614D03*
X863346Y307602D03*
X863441Y282602D03*
X899941Y283917D03*
Y278917D03*
X876441Y626732D03*
Y617283D03*
X863441Y618614D03*
X899941Y624429D03*
Y609429D03*
X876441Y661378D03*
Y651929D03*
Y642480D03*
Y636181D03*
X863287Y675114D03*
X863441Y688114D03*
X876441Y696023D03*
Y686575D03*
Y677126D03*
Y667677D03*
X899941Y684429D03*
Y639429D03*
Y689429D03*
X876441Y724370D03*
Y714921D03*
Y705472D03*
X863397Y707114D03*
X876441Y1066890D03*
Y1057441D03*
Y1047992D03*
Y1041693D03*
Y1032244D03*
Y1022795D03*
X863441Y1024126D03*
X899941Y1044941D03*
Y1029941D03*
Y1014941D03*
X876441Y1129882D03*
Y1120433D03*
Y1110984D03*
Y1101535D03*
Y1092087D03*
Y1082638D03*
Y1073189D03*
X863308Y1075126D03*
X863441Y1093626D03*
X863346Y1118626D03*
X899941Y1094941D03*
Y1089941D03*
X876441Y1428307D03*
X863441Y1429638D03*
X899941Y1420453D03*
X876441Y1478701D03*
Y1472402D03*
Y1462953D03*
Y1453504D03*
Y1447205D03*
Y1437756D03*
Y1497599D03*
Y1488150D03*
X863286Y1486138D03*
X863441Y1499138D03*
X899941Y1450453D03*
Y1435453D03*
Y1500453D03*
Y1495453D03*
X876441Y1535394D03*
Y1525945D03*
Y1516496D03*
Y1507047D03*
X863347Y1524138D03*
X876441Y1859016D03*
Y1852717D03*
Y1843268D03*
Y1833819D03*
X863441Y1835150D03*
X899941Y1855965D03*
Y1840965D03*
Y1825965D03*
X876441Y1912559D03*
Y1903111D03*
Y1893662D03*
Y1884213D03*
Y1877914D03*
Y1868465D03*
X863287Y1891650D03*
X863441Y1904650D03*
X876441Y1931457D03*
Y1922008D03*
X863346Y1929650D03*
X899941Y1905965D03*
Y1900965D03*
X876441Y1940906D03*
G54D24*
X97400Y366600D03*
X97000Y772100D03*
X96100Y1176700D03*
X88076Y1575924D03*
X43935Y1957215D03*
X824335Y365915D03*
Y771415D03*
Y1176915D03*
Y1582415D03*
X774989Y1955708D03*
G54D25*
X95849Y361564D03*
X87900Y1173300D03*
X56875Y1954250D03*
X182000Y949000D03*
X292200Y1688900D03*
X295800D03*
X374300Y81400D03*
X378100Y81500D03*
X414281Y820751D03*
X421000Y812750D03*
X420743Y1215266D03*
X414274Y1223246D03*
X421000Y1713750D03*
X414299Y1721750D03*
X815375Y362750D03*
Y768250D03*
Y1173750D03*
X816625Y1579250D03*
X780214Y1953257D03*
G54D27*
X145900Y408500D03*
X147100Y814200D03*
X146700Y1219600D03*
X143500Y1625500D03*
X196665Y35585D03*
G54D15*
X24500Y619093D03*
Y606544D03*
Y694733D03*
Y682135D03*
Y669537D03*
Y644340D03*
Y631741D03*
Y763825D03*
Y732329D03*
Y719730D03*
Y707332D03*
Y848664D03*
Y836266D03*
Y823667D03*
Y811069D03*
Y798470D03*
Y776423D03*
Y911856D03*
Y899258D03*
Y886509D03*
Y873861D03*
Y861263D03*
Y1133365D03*
Y1095769D03*
Y1108368D03*
Y1208955D03*
Y1196357D03*
Y1183758D03*
Y1171160D03*
Y1158562D03*
Y1145963D03*
Y1278247D03*
Y1265648D03*
Y1253050D03*
Y1221554D03*
Y1350888D03*
Y1338289D03*
Y1325691D03*
Y1313092D03*
Y1290845D03*
Y1401081D03*
Y1388483D03*
Y1375884D03*
Y1363286D03*
Y1566907D03*
Y1554308D03*
Y1529111D03*
Y1541710D03*
Y1639348D03*
Y1626749D03*
Y1614151D03*
Y1601552D03*
Y1588954D03*
Y1702531D03*
Y1689932D03*
Y1677334D03*
Y1762373D03*
Y1749775D03*
Y1737176D03*
Y1724578D03*
X109038Y62310D03*
X109000Y81106D03*
X109160Y105900D03*
X67500Y124088D03*
X108917Y150188D03*
X109044Y467822D03*
X109000Y486618D03*
X109138Y505912D03*
X67500Y529600D03*
X108917Y555700D03*
X109040Y873334D03*
X109000Y892130D03*
X109187Y911424D03*
X67500Y935111D03*
X109000Y961212D03*
X109040Y1278846D03*
X109000Y1297642D03*
X109133Y1316936D03*
X67500Y1340624D03*
X109000Y1366724D03*
X109040Y1684358D03*
X109000Y1703154D03*
X109137Y1722448D03*
X67500Y1757886D03*
X109030Y1778736D03*
X194500Y236902D03*
X190600Y1045226D03*
X190400Y1462536D03*
X194620Y1859298D03*
X921400Y235002D03*
X919000Y639715D03*
X922900Y1048050D03*
X919000Y1450734D03*
Y1856251D03*
G54D26*
X87075Y768250D03*
%LPC*%
G75*
G54D30*
G01X-90900Y-277455D02*
Y-294955D01*
X-82166D01*
G01X-69033Y-283289D02*
Y-294955D01*
G01Y-278622D02*
X-69470Y-278330D01*
Y-277747D01*
X-69033Y-277455D01*
X-68596Y-277747D01*
Y-278330D01*
X-69033Y-278622D01*
G01X-54590Y-299330D02*
X-53061Y-300497D01*
X-51315Y-300788D01*
X-49787Y-300497D01*
X-48476Y-299039D01*
X-47603Y-296997D01*
Y-283289D01*
G01Y-285622D02*
X-48476Y-284455D01*
X-49787Y-283580D01*
X-51315Y-283289D01*
X-53061Y-283872D01*
X-54153Y-285038D01*
X-55027Y-287080D01*
X-55463Y-289122D01*
X-55245Y-290872D01*
X-54371Y-292914D01*
X-53061Y-294372D01*
X-51315Y-294955D01*
X-50005Y-294663D01*
X-48476Y-293497D01*
X-47603Y-292331D01*
G01X-37745Y-294955D02*
Y-277455D01*
G01Y-285913D02*
X-36653Y-284455D01*
X-35561Y-283580D01*
X-33815Y-283289D01*
X-32505Y-283580D01*
X-30976Y-284747D01*
X-30321Y-286497D01*
Y-294955D01*
G01X-16533Y-277455D02*
Y-294955D01*
G01X-19590Y-283289D02*
X-13476D01*
G01X-2745Y-294955D02*
Y-283289D01*
G01Y-286205D02*
X-1871Y-284747D01*
X-561Y-283580D01*
X1185Y-283289D01*
X2713Y-283580D01*
X4024Y-284747D01*
X4679Y-286788D01*
Y-294955D01*
G01X18467Y-283289D02*
Y-294955D01*
G01Y-278622D02*
X18030Y-278330D01*
Y-277747D01*
X18467Y-277455D01*
X18904Y-277747D01*
Y-278330D01*
X18467Y-278622D01*
G01X32255Y-294955D02*
Y-283289D01*
G01Y-286205D02*
X33129Y-284747D01*
X34439Y-283580D01*
X36185Y-283289D01*
X37713Y-283580D01*
X39024Y-284747D01*
X39679Y-286788D01*
Y-294955D01*
G01X50410Y-299330D02*
X51939Y-300497D01*
X53685Y-300788D01*
X55213Y-300497D01*
X56524Y-299039D01*
X57397Y-296997D01*
Y-283289D01*
G01Y-285622D02*
X56524Y-284455D01*
X55213Y-283580D01*
X53685Y-283289D01*
X51939Y-283872D01*
X50847Y-285038D01*
X49973Y-287080D01*
X49537Y-289122D01*
X49755Y-290872D01*
X50629Y-292914D01*
X51939Y-294372D01*
X53685Y-294955D01*
X54995Y-294663D01*
X56524Y-293497D01*
X57397Y-292331D01*
G01X84100Y-294955D02*
Y-277455D01*
X89340D01*
X91087Y-278330D01*
X92397Y-280372D01*
X92834Y-282705D01*
X92397Y-285038D01*
X91305Y-286788D01*
X89340Y-287664D01*
X84100D01*
G01X101164Y-294955D02*
Y-277455D01*
X105530D01*
X107277Y-278330D01*
X108587Y-279497D01*
X109679Y-281246D01*
X110552Y-283289D01*
X110770Y-286205D01*
X110552Y-289122D01*
X109679Y-291164D01*
X108587Y-292914D01*
X107277Y-294080D01*
X105530Y-294955D01*
X101164D01*
G01X119100D02*
Y-277455D01*
X124340D01*
X126087Y-278330D01*
X127397Y-280372D01*
X127834Y-282705D01*
X127397Y-285038D01*
X126305Y-286788D01*
X124340Y-287664D01*
X119100D01*
G01X142713Y-285622D02*
X143587Y-284747D01*
X144242Y-283289D01*
X144679Y-281246D01*
X144242Y-279497D01*
X143369Y-278330D01*
X141840Y-277455D01*
X135945D01*
Y-294955D01*
X143150D01*
X144679Y-293789D01*
X145552Y-292038D01*
X145989Y-289997D01*
X145552Y-287955D01*
X144242Y-286205D01*
X142713Y-285622D01*
X135945D01*
G01X171600Y-294955D02*
Y-277455D01*
X176840D01*
X178587Y-278330D01*
X179897Y-280372D01*
X180334Y-282705D01*
X179897Y-285038D01*
X178805Y-286788D01*
X176840Y-287664D01*
X171600D01*
G01X188008Y-277455D02*
X193467Y-294955D01*
X198926Y-277455D01*
G01X210967D02*
Y-294955D01*
G01X205945Y-277455D02*
X215989D01*
G01X21540Y-249955D02*
Y-232455D01*
X27217Y-247038D01*
X32894Y-232455D01*
Y-249955D01*
G01X44717D02*
X43407Y-249663D01*
X42097Y-248497D01*
X41223Y-246455D01*
X40787Y-244122D01*
X41223Y-241788D01*
X42097Y-239747D01*
X43407Y-238580D01*
X44717Y-238289D01*
X46027Y-238580D01*
X47337Y-239747D01*
X48210Y-241788D01*
X48429Y-244122D01*
X48210Y-246455D01*
X47337Y-248497D01*
X46027Y-249663D01*
X44717Y-249955D01*
G01X66147Y-232455D02*
Y-249955D01*
G01Y-247331D02*
X65274Y-248789D01*
X63963Y-249663D01*
X62435Y-249955D01*
X60689Y-249372D01*
X59379Y-247914D01*
X58505Y-246164D01*
X58287Y-244122D01*
X58505Y-242080D01*
X59379Y-240330D01*
X60689Y-238872D01*
X62435Y-238289D01*
X63963Y-238580D01*
X65055Y-239164D01*
X66147Y-240330D01*
G01X76442Y-242080D02*
X83429D01*
X82774Y-240038D01*
X81682Y-238872D01*
X80154Y-238289D01*
X78625Y-238580D01*
X77315Y-239455D01*
X76442Y-241497D01*
X76005Y-243247D01*
Y-244997D01*
X76442Y-246747D01*
X77534Y-248497D01*
X78844Y-249663D01*
X80372Y-249955D01*
X81900Y-249372D01*
X83429Y-247622D01*
G01X97217Y-249955D02*
Y-232455D01*
G01X252500Y-249955D02*
Y-232455D01*
X257740D01*
X259487Y-233330D01*
X260797Y-235372D01*
X261234Y-237705D01*
X260797Y-240038D01*
X259705Y-241788D01*
X257740Y-242664D01*
X252500D01*
G01X279170Y-233914D02*
X277860Y-233038D01*
X276332Y-232455D01*
X274585D01*
X272620Y-233330D01*
X271092Y-234788D01*
X270000Y-236539D01*
X269127Y-239455D01*
X268908Y-242080D01*
X269345Y-244705D01*
X270000Y-246455D01*
X271310Y-248205D01*
X272839Y-249372D01*
X274367Y-249955D01*
X275895D01*
X277424Y-249372D01*
X278734Y-248497D01*
X279826Y-247331D01*
G01X293613Y-240622D02*
X294487Y-239747D01*
X295142Y-238289D01*
X295579Y-236246D01*
X295142Y-234497D01*
X294269Y-233330D01*
X292740Y-232455D01*
X286845D01*
Y-249955D01*
X294050D01*
X295579Y-248789D01*
X296452Y-247038D01*
X296889Y-244997D01*
X296452Y-242955D01*
X295142Y-241205D01*
X293613Y-240622D01*
X286845D01*
G01X302817Y-255788D02*
X315917D01*
G01X321845Y-249955D02*
Y-232455D01*
X331889Y-249955D01*
Y-232455D01*
G01X344367Y-249955D02*
X342620Y-249663D01*
X341092Y-248497D01*
X339782Y-246747D01*
X338908Y-244705D01*
X338472Y-242372D01*
Y-240038D01*
X338908Y-237705D01*
X339782Y-235663D01*
X341092Y-233914D01*
X342620Y-232747D01*
X344367Y-232455D01*
X346113Y-232747D01*
X347642Y-233914D01*
X348952Y-235663D01*
X349826Y-237705D01*
X350262Y-240038D01*
Y-242372D01*
X349826Y-244705D01*
X348952Y-246747D01*
X347642Y-248497D01*
X346113Y-249663D01*
X344367Y-249955D01*
G01X265617Y-294955D02*
Y-277455D01*
X262997Y-280955D01*
G01Y-294955D02*
X268237D01*
G01X278314Y-292331D02*
X279623Y-293789D01*
X281152Y-294663D01*
X283117Y-294955D01*
X285082Y-294372D01*
X286610Y-293205D01*
X287702Y-291164D01*
X287920Y-288830D01*
X287484Y-286497D01*
X286392Y-285038D01*
X284863Y-283872D01*
X283335Y-283580D01*
X281807Y-283872D01*
X279842Y-285038D01*
X280497Y-277455D01*
X286392D01*
G01X296469Y-287664D02*
X297997Y-285622D01*
X299307Y-284455D01*
X301054Y-283872D01*
X302582Y-284455D01*
X303674Y-285622D01*
X304547Y-287372D01*
X304765Y-289413D01*
X304547Y-291164D01*
X303674Y-292914D01*
X302363Y-294372D01*
X300835Y-294955D01*
X299089Y-294372D01*
X297560Y-292622D01*
X296687Y-289997D01*
X296469Y-287080D01*
X296905Y-283289D01*
X297560Y-281246D01*
X298652Y-279205D01*
X300180Y-277747D01*
X301709Y-277455D01*
X303237Y-278038D01*
X304329Y-279497D01*
G01X313969Y-287664D02*
X315497Y-285622D01*
X316807Y-284455D01*
X318554Y-283872D01*
X320082Y-284455D01*
X321174Y-285622D01*
X322047Y-287372D01*
X322265Y-289413D01*
X322047Y-291164D01*
X321174Y-292914D01*
X319863Y-294372D01*
X318335Y-294955D01*
X316589Y-294372D01*
X315060Y-292622D01*
X314187Y-289997D01*
X313969Y-287080D01*
X314405Y-283289D01*
X315060Y-281246D01*
X316152Y-279205D01*
X317680Y-277747D01*
X319209Y-277455D01*
X320737Y-278038D01*
X321829Y-279497D01*
G01X331905Y-292914D02*
X333434Y-294372D01*
X335180Y-294955D01*
X336927Y-294372D01*
X338455Y-292622D01*
X339547Y-289997D01*
X339984Y-287372D01*
Y-284164D01*
X339547Y-281539D01*
X338455Y-279205D01*
X337145Y-278038D01*
X335617Y-277455D01*
X333870Y-278038D01*
X332560Y-279205D01*
X331687Y-280955D01*
X331250Y-283289D01*
X331687Y-285330D01*
X332779Y-287372D01*
X334089Y-288539D01*
X335617Y-288830D01*
X337363Y-288247D01*
X338674Y-286788D01*
X339984Y-284164D01*
G01X395208Y-232455D02*
X400667Y-249955D01*
X406126Y-232455D01*
G01X422534Y-249955D02*
X413800D01*
Y-232455D01*
X422534D01*
G01X419040Y-240913D02*
X413800D01*
G01X431300Y-249955D02*
Y-232455D01*
X436759D01*
X438505Y-233330D01*
X439597Y-234497D01*
X440034Y-236830D01*
X439597Y-239164D01*
X438287Y-240622D01*
X436759Y-241497D01*
X431300D01*
G01X436759D02*
X440034Y-249955D01*
G01X453167Y-250538D02*
X452730Y-250247D01*
Y-249663D01*
X453167Y-249372D01*
X453604Y-249663D01*
Y-250247D01*
X453167Y-250538D01*
G01X426917Y-294955D02*
Y-277455D01*
X424297Y-280955D01*
G01Y-294955D02*
X429537D01*
G01X528750Y-232455D02*
Y-249955D01*
X537484D01*
G01X554547D02*
Y-238289D01*
G01Y-240330D02*
X553674Y-239164D01*
X552363Y-238580D01*
X550835Y-238289D01*
X549307Y-238872D01*
X547997Y-240038D01*
X547123Y-241788D01*
X546687Y-244122D01*
X547123Y-246455D01*
X547997Y-248205D01*
X549307Y-249372D01*
X550835Y-249955D01*
X552363Y-249663D01*
X553674Y-248789D01*
X554547Y-247622D01*
G01X563532Y-255205D02*
X564842Y-255788D01*
X566589Y-255205D01*
X567680Y-254039D01*
X568554Y-252580D01*
X569863Y-247914D01*
X572702Y-238289D01*
G01X565715D02*
X569863Y-247914D01*
G01X582342Y-242080D02*
X589329D01*
X588674Y-240038D01*
X587582Y-238872D01*
X586054Y-238289D01*
X584525Y-238580D01*
X583215Y-239455D01*
X582342Y-241497D01*
X581905Y-243247D01*
Y-244997D01*
X582342Y-246747D01*
X583434Y-248497D01*
X584744Y-249663D01*
X586272Y-249955D01*
X587800Y-249372D01*
X589329Y-247622D01*
G01X600060Y-249955D02*
Y-238289D01*
G01Y-240622D02*
X601152Y-239455D01*
X602244Y-238580D01*
X603772Y-238289D01*
X604863Y-238580D01*
X606174Y-239455D01*
G01X528750Y-277455D02*
Y-294955D01*
X537484D01*
G01X553237D02*
Y-277455D01*
X545158Y-289997D01*
X556076D01*
G01X562658Y-277455D02*
X568117Y-294955D01*
X573576Y-277455D01*
G01X590420Y-278914D02*
X589110Y-278038D01*
X587582Y-277455D01*
X585835D01*
X583870Y-278330D01*
X582342Y-279788D01*
X581250Y-281539D01*
X580377Y-284455D01*
X580158Y-287080D01*
X580595Y-289705D01*
X581250Y-291455D01*
X582560Y-293205D01*
X584089Y-294372D01*
X585617Y-294955D01*
X587145D01*
X588674Y-294372D01*
X589984Y-293497D01*
X591076Y-292331D01*
G01X607920Y-278914D02*
X606610Y-278038D01*
X605082Y-277455D01*
X603335D01*
X601370Y-278330D01*
X599842Y-279788D01*
X598750Y-281539D01*
X597877Y-284455D01*
X597658Y-287080D01*
X598095Y-289705D01*
X598750Y-291455D01*
X600060Y-293205D01*
X601589Y-294372D01*
X603117Y-294955D01*
X604645D01*
X606174Y-294372D01*
X607484Y-293497D01*
X608576Y-292331D01*
G01X670864Y-249955D02*
Y-232455D01*
X675230D01*
X676977Y-233330D01*
X678287Y-234497D01*
X679379Y-236246D01*
X680252Y-238289D01*
X680470Y-241205D01*
X680252Y-244122D01*
X679379Y-246164D01*
X678287Y-247914D01*
X676977Y-249080D01*
X675230Y-249955D01*
X670864D01*
G01X689892Y-242080D02*
X696879D01*
X696224Y-240038D01*
X695132Y-238872D01*
X693604Y-238289D01*
X692075Y-238580D01*
X690765Y-239455D01*
X689892Y-241497D01*
X689455Y-243247D01*
Y-244997D01*
X689892Y-246747D01*
X690984Y-248497D01*
X692294Y-249663D01*
X693822Y-249955D01*
X695350Y-249372D01*
X696879Y-247622D01*
G01X707392Y-247914D02*
X708484Y-249080D01*
X710012Y-249955D01*
X711322D01*
X712632Y-249372D01*
X713505Y-248497D01*
X713942Y-247331D01*
X713724Y-245580D01*
X712850Y-244705D01*
X708920Y-242955D01*
X708047Y-240913D01*
X708484Y-239455D01*
X709357Y-238580D01*
X710667Y-238289D01*
X711977Y-238580D01*
X713287Y-239455D01*
G01X728167Y-238289D02*
Y-249955D01*
G01Y-233622D02*
X727730Y-233330D01*
Y-232747D01*
X728167Y-232455D01*
X728604Y-232747D01*
Y-233330D01*
X728167Y-233622D01*
G01X742610Y-254330D02*
X744139Y-255497D01*
X745885Y-255788D01*
X747413Y-255497D01*
X748724Y-254039D01*
X749597Y-251997D01*
Y-238289D01*
G01Y-240622D02*
X748724Y-239455D01*
X747413Y-238580D01*
X745885Y-238289D01*
X744139Y-238872D01*
X743047Y-240038D01*
X742173Y-242080D01*
X741737Y-244122D01*
X741955Y-245872D01*
X742829Y-247914D01*
X744139Y-249372D01*
X745885Y-249955D01*
X747195Y-249663D01*
X748724Y-248497D01*
X749597Y-247331D01*
G01X759455Y-249955D02*
Y-238289D01*
G01Y-241205D02*
X760329Y-239747D01*
X761639Y-238580D01*
X763385Y-238289D01*
X764913Y-238580D01*
X766224Y-239747D01*
X766879Y-241788D01*
Y-249955D01*
G01X777392Y-242080D02*
X784379D01*
X783724Y-240038D01*
X782632Y-238872D01*
X781104Y-238289D01*
X779575Y-238580D01*
X778265Y-239455D01*
X777392Y-241497D01*
X776955Y-243247D01*
Y-244997D01*
X777392Y-246747D01*
X778484Y-248497D01*
X779794Y-249663D01*
X781322Y-249955D01*
X782850Y-249372D01*
X784379Y-247622D01*
G01X795110Y-249955D02*
Y-238289D01*
G01Y-240622D02*
X796202Y-239455D01*
X797294Y-238580D01*
X798822Y-238289D01*
X799913Y-238580D01*
X801224Y-239455D01*
G01X660367Y-277455D02*
X663423Y-294955D01*
X666917Y-277455D01*
X670410Y-294955D01*
X673467Y-277455D01*
G01X680050Y-294955D02*
Y-277455D01*
X685290D01*
X687037Y-278330D01*
X688347Y-280372D01*
X688784Y-282705D01*
X688347Y-285038D01*
X687255Y-286788D01*
X685290Y-287664D01*
X680050D01*
G01X697332Y-294955D02*
Y-277455D01*
G01X706502D02*
Y-294955D01*
G01Y-286205D02*
X697332D01*
G01X716579Y-289122D02*
X722255D01*
G01X732769Y-294955D02*
Y-277455D01*
X741065D01*
G01X738009Y-285913D02*
X732769D01*
G01X750050Y-277455D02*
Y-294955D01*
X758784D01*
G01X771917D02*
X770170Y-294663D01*
X768642Y-293497D01*
X767332Y-291747D01*
X766458Y-289705D01*
X766022Y-287372D01*
Y-285038D01*
X766458Y-282705D01*
X767332Y-280663D01*
X768642Y-278914D01*
X770170Y-277747D01*
X771917Y-277455D01*
X773663Y-277747D01*
X775192Y-278914D01*
X776502Y-280663D01*
X777376Y-282705D01*
X777812Y-285038D01*
Y-287372D01*
X777376Y-289705D01*
X776502Y-291747D01*
X775192Y-293497D01*
X773663Y-294663D01*
X771917Y-294955D01*
G01X785050D02*
Y-277455D01*
X790509D01*
X792255Y-278330D01*
X793347Y-279497D01*
X793784Y-281830D01*
X793347Y-284164D01*
X792037Y-285622D01*
X790509Y-286497D01*
X785050D01*
G01X790509D02*
X793784Y-294955D01*
G01X801458D02*
X806917Y-277455D01*
X812376Y-294955D01*
G01X810410Y-288830D02*
X803423D01*
G01X841867Y-294955D02*
Y-277455D01*
X839247Y-280955D01*
G01Y-294955D02*
X844487D01*
G01X859367D02*
Y-277455D01*
X856747Y-280955D01*
G01Y-294955D02*
X861987D01*
G01X872937Y-295538D02*
X880797Y-277455D01*
G01X894367Y-294955D02*
Y-277455D01*
X891747Y-280955D01*
G01Y-294955D02*
X896987D01*
G01X907719Y-287664D02*
X909247Y-285622D01*
X910557Y-284455D01*
X912304Y-283872D01*
X913832Y-284455D01*
X914924Y-285622D01*
X915797Y-287372D01*
X916015Y-289413D01*
X915797Y-291164D01*
X914924Y-292914D01*
X913613Y-294372D01*
X912085Y-294955D01*
X910339Y-294372D01*
X908810Y-292622D01*
X907937Y-289997D01*
X907719Y-287080D01*
X908155Y-283289D01*
X908810Y-281246D01*
X909902Y-279205D01*
X911430Y-277747D01*
X912959Y-277455D01*
X914487Y-278038D01*
X915579Y-279497D01*
G01X925437Y-295538D02*
X933297Y-277455D01*
G01X942719Y-280372D02*
X944029Y-278622D01*
X945557Y-277747D01*
X947304Y-277455D01*
X949487Y-278038D01*
X951015Y-279497D01*
X951452Y-281246D01*
X951234Y-282997D01*
X950360Y-284455D01*
X945994Y-287372D01*
X944029Y-289413D01*
X942719Y-292331D01*
X942282Y-294955D01*
X951452D01*
G01X964367Y-277455D02*
X962620Y-278038D01*
X961310Y-279497D01*
X960437Y-281246D01*
X959782Y-283580D01*
X959564Y-286205D01*
X959782Y-288830D01*
X960437Y-291164D01*
X961310Y-292914D01*
X962620Y-294372D01*
X964367Y-294955D01*
X966113Y-294372D01*
X967424Y-292914D01*
X968297Y-291164D01*
X968952Y-288830D01*
X969170Y-286205D01*
X968952Y-283580D01*
X968297Y-281246D01*
X967424Y-279497D01*
X966113Y-278038D01*
X964367Y-277455D01*
G01X981867Y-294955D02*
Y-277455D01*
X979247Y-280955D01*
G01Y-294955D02*
X984487D01*
G01X995219Y-287664D02*
X996747Y-285622D01*
X998057Y-284455D01*
X999804Y-283872D01*
X1001332Y-284455D01*
X1002424Y-285622D01*
X1003297Y-287372D01*
X1003515Y-289413D01*
X1003297Y-291164D01*
X1002424Y-292914D01*
X1001113Y-294372D01*
X999585Y-294955D01*
X997839Y-294372D01*
X996310Y-292622D01*
X995437Y-289997D01*
X995219Y-287080D01*
X995655Y-283289D01*
X996310Y-281246D01*
X997402Y-279205D01*
X998930Y-277747D01*
X1000459Y-277455D01*
X1001987Y-278038D01*
X1003079Y-279497D01*
G01X889564Y-249955D02*
Y-232455D01*
X893930D01*
X895677Y-233330D01*
X896987Y-234497D01*
X898079Y-236246D01*
X898952Y-238289D01*
X899170Y-241205D01*
X898952Y-244122D01*
X898079Y-246164D01*
X896987Y-247914D01*
X895677Y-249080D01*
X893930Y-249955D01*
X889564D01*
G01X915797D02*
Y-238289D01*
G01Y-240330D02*
X914924Y-239164D01*
X913613Y-238580D01*
X912085Y-238289D01*
X910557Y-238872D01*
X909247Y-240038D01*
X908373Y-241788D01*
X907937Y-244122D01*
X908373Y-246455D01*
X909247Y-248205D01*
X910557Y-249372D01*
X912085Y-249955D01*
X913613Y-249663D01*
X914924Y-248789D01*
X915797Y-247622D01*
G01X929367Y-232455D02*
Y-249955D01*
G01X926310Y-238289D02*
X932424D01*
G01X943592Y-242080D02*
X950579D01*
X949924Y-240038D01*
X948832Y-238872D01*
X947304Y-238289D01*
X945775Y-238580D01*
X944465Y-239455D01*
X943592Y-241497D01*
X943155Y-243247D01*
Y-244997D01*
X943592Y-246747D01*
X944684Y-248497D01*
X945994Y-249663D01*
X947522Y-249955D01*
X949050Y-249372D01*
X950579Y-247622D01*
G54D29*
G01X-106883Y-224955D02*
Y-304955D01*
G01Y-260455D02*
X1019417D01*
G01X-106883Y-304955D02*
X1019417D01*
G01X-110883Y-208955D02*
G02I-12000J0D01*
G01X-116033D02*
G02I-6850J0D01*
G01X-122883Y-224955D02*
Y-192955D01*
G01X-106883Y-208955D02*
X-138883D01*
G01X-106883Y-224955D02*
X1019417D01*
G01X231917D02*
Y-304955D01*
G01X369417Y-224955D02*
Y-304955D01*
G01X484417Y-224955D02*
Y-304955D01*
G01X651917Y-224955D02*
Y-304955D01*
G01X821917Y-224955D02*
Y-304955D01*
G01X1019417Y-224955D02*
Y-304955D01*
G01X1047417Y-208955D02*
G02I-12000J0D01*
G01X1042267D02*
G02I-6850J0D01*
G01X1035417Y-224955D02*
Y-192955D01*
G01X1051417Y-208955D02*
X1019417D01*
M02*
